FILE_TYPE = MACRO_DRAWING;
SET COLOR_WIRE YELLOW;
SET COLOR_PROP MONO;
SET COLOR_DOT WHITE;
SET COLOR_ARC YELLOW;
SET COLOR_BODY GREEN;
SET COLOR_NOTE MONO;
SET PROP_DISPLAY VALUE;
SET PAGE_NUMBER P157;
FORCEADD OFFPAGE..2
(-5975 4225);
FORCEPROP 2 LAST $XR2 146 
J 0
(-5546 4225);
DISPLAY 0.638298 (-5546 4225);
PAINT MONO (-5546 4225);
FORCEPROP 2 LAST $XR1 119 
J 0
(-5666 4225);
DISPLAY 0.638298 (-5666 4225);
PAINT MONO (-5666 4225);
FORCEPROP 2 LAST $XR0 186 
J 0
(-5786 4225);
DISPLAY 0.638298 (-5786 4225);
PAINT MONO (-5786 4225);
FORCEPROP 2 LAST PATH I293
J 0
(-5800 4300);
DISPLAY 1.021277 (-5800 4300);
PAINT ORANGE (-5800 4300);
DISPLAY INVISIBLE (-5800 4300);
FORCEPROP 1 LAST OFFPAGE TRUE
J 0
(-5650 4100);
DISPLAY 0.872340 (-5650 4100);
PAINT GREEN (-5650 4100);
DISPLAY INVISIBLE (-5650 4100);
FORCEPROP 1 LAST COMMENT_BODY TRUE
J 0
(-6020 4130);
DISPLAY 0.872340 (-6020 4130);
PAINT GREEN (-6020 4130);
DISPLAY INVISIBLE (-6020 4130);
FORCEPROP 2 LAST CDS_LIB mstr_standard
J 0
(-5975 4225);
PAINT ORANGE (-5975 4225);
DISPLAY INVISIBLE (-5975 4225);
FORCEADD RES..1
(-7200 4225);
FORCEPROP 1 LAST TOLERANCE 1%
J 0
(-7150 4175);
DISPLAY 0.617021 (-7150 4175);
PAINT SKYBLUE (-7150 4175);
FORCEPROP 1 LAST PACK_TYPE 0402
J 0
(-7025 4175);
DISPLAY 0.617021 (-7025 4175);
PAINT SKYBLUE (-7025 4175);
FORCEPROP 1 LAST MATERIAL CHIP
J 0
(-6950 4150);
DISPLAY 0.617021 (-6950 4150);
PAINT SKYBLUE (-6950 4150);
FORCEPROP 1 LAST WATTAGE 1/16W
J 2
(-6750 4175);
DISPLAY 0.617021 (-6750 4175);
PAINT SKYBLUE (-6750 4175);
FORCEPROP 1 LASTPIN (-7100 4225) $PN 2
J 0
(-7138 4237);
DISPLAY 0.617021 (-7138 4237);
PAINT ORANGE (-7138 4237);
FORCEPROP 1 LAST LOCATION R8F23
J 0
(-7250 4275);
DISPLAY 0.617021 (-7250 4275);
PAINT AQUA (-7250 4275);
FORCEPROP 1 LAST PART_NUMBER G21796-112
J 0
(-7425 4125);
DISPLAY 0.617021 (-7425 4125);
PAINT BLUE (-7425 4125);
FORCEPROP 1 LAST VALUE 2.21K
J 2
(-7225 4175);
DISPLAY 0.617021 (-7225 4175);
PAINT SKYBLUE (-7225 4175);
FORCEPROP 1 LASTPIN (-7300 4225) $PN 1
J 0
(-7288 4237);
DISPLAY 0.617021 (-7288 4237);
PAINT ORANGE (-7288 4237);
FORCEPROP 2 LAST BOM_COST SM_CONTROLLER
J 0
(-7250 4375);
DISPLAY 1.021277 (-7250 4375);
PAINT ORANGE (-7250 4375);
DISPLAY INVISIBLE (-7250 4375);
FORCEPROP 2 LAST SEC_TYPE 0402
J 0
(-7250 4425);
DISPLAY 1.021277 (-7250 4425);
PAINT ORANGE (-7250 4425);
DISPLAY INVISIBLE (-7250 4425);
FORCEPROP 1 LAST PATH I296
J 0
(-7250 4375);
DISPLAY 0.978723 (-7250 4375);
PAINT WHITE (-7250 4375);
DISPLAY INVISIBLE (-7250 4375);
FORCEPROP 0 LAST SEC 1
J 0
(-7250 4325);
DISPLAY 0.680851 (-7250 4325);
PAINT MONO (-7250 4325);
DISPLAY INVISIBLE (-7250 4325);
FORCEPROP 2 LAST ROOM BMC_MISC
J 0
(-7250 4325);
DISPLAY 1.021277 (-7250 4325);
PAINT ORANGE (-7250 4325);
DISPLAY INVISIBLE (-7250 4325);
FORCEPROP 2 LAST CDS_LOCATION R8F23
J 0
(-7250 4275);
DISPLAY 0.617021 (-7250 4275);
PAINT AQUA (-7250 4275);
DISPLAY INVISIBLE (-7250 4275);
FORCEPROP 2 LAST CDS_LIB mstr_discrete
J 0
(-7200 4225);
PAINT ORANGE (-7200 4225);
DISPLAY INVISIBLE (-7200 4225);
FORCEADD P3V3_STBY..1
(-7525 4650);
FORCEPROP 3 LASTPIN (-7525 4600) SIG_NAME P3V3_STBY\g
J 0
(-7515 4610);
DISPLAY 0.659574 (-7515 4610);
PAINT MONO (-7515 4610);
DISPLAY INVISIBLE (-7515 4610);
FORCEPROP 2 LAST CDS_LIB mstr_symbols
J 0
(-7525 4650);
PAINT ORANGE (-7525 4650);
DISPLAY INVISIBLE (-7525 4650);
FORCEPROP 1 LAST SIZE 1B
J 0
(-7480 4672);
DISPLAY 0.340426 (-7480 4672);
PAINT GREEN (-7480 4672);
DISPLAY INVISIBLE (-7480 4672);
FORCEPROP 1 LAST PATH I297
J 0
(-7480 4652);
DISPLAY 0.340426 (-7480 4652);
PAINT GREEN (-7480 4652);
DISPLAY INVISIBLE (-7480 4652);
FORCEPROP 1 LAST VOLTAGE 3.3V
J 0
(-7570 4607);
DISPLAY 0.340426 (-7570 4607);
PAINT SKYBLUE (-7570 4607);
DISPLAY INVISIBLE (-7570 4607);
FORCEPROP 1 LAST BODY_TYPE PLUMBING
J 0
(-7570 4607);
DISPLAY 0.340426 (-7570 4607);
PAINT GREEN (-7570 4607);
DISPLAY INVISIBLE (-7570 4607);
FORCEPROP 1 LAST HDL_POWER P3V3_STBY
J 0
(-7825 4525);
DISPLAY 0.872340 (-7825 4525);
PAINT ORANGE (-7825 4525);
DISPLAY INVISIBLE (-7825 4525);
FORCEADD RES..1
(-7175 3975);
FORCEPROP 1 LAST WATTAGE 1/16W
J 2
(-6725 3925);
DISPLAY 0.617021 (-6725 3925);
PAINT SKYBLUE (-6725 3925);
FORCEPROP 1 LAST MATERIAL CHIP
J 0
(-6925 3900);
DISPLAY 0.617021 (-6925 3900);
PAINT SKYBLUE (-6925 3900);
FORCEPROP 1 LAST PACK_TYPE 0402
J 0
(-7000 3925);
DISPLAY 0.617021 (-7000 3925);
PAINT SKYBLUE (-7000 3925);
FORCEPROP 1 LASTPIN (-7075 3975) $PN 2
J 0
(-7113 3987);
DISPLAY 0.617021 (-7113 3987);
PAINT ORANGE (-7113 3987);
FORCEPROP 1 LAST TOLERANCE 1%
J 0
(-7125 3925);
DISPLAY 0.617021 (-7125 3925);
PAINT SKYBLUE (-7125 3925);
FORCEPROP 1 LAST LOCATION R2T29
J 0
(-7225 4025);
DISPLAY 0.617021 (-7225 4025);
PAINT AQUA (-7225 4025);
FORCEPROP 1 LAST PART_NUMBER G21796-112
J 0
(-7400 3875);
DISPLAY 0.617021 (-7400 3875);
PAINT BLUE (-7400 3875);
FORCEPROP 1 LAST VALUE 2.21K
J 2
(-7200 3925);
DISPLAY 0.617021 (-7200 3925);
PAINT SKYBLUE (-7200 3925);
FORCEPROP 1 LASTPIN (-7275 3975) $PN 1
J 0
(-7263 3987);
DISPLAY 0.617021 (-7263 3987);
PAINT ORANGE (-7263 3987);
FORCEPROP 2 LAST BOM_COST SM_CONTROLLER
J 0
(-7225 4125);
DISPLAY 1.021277 (-7225 4125);
PAINT ORANGE (-7225 4125);
DISPLAY INVISIBLE (-7225 4125);
FORCEPROP 1 LAST PATH I298
J 0
(-7225 4125);
DISPLAY 0.978723 (-7225 4125);
PAINT WHITE (-7225 4125);
DISPLAY INVISIBLE (-7225 4125);
FORCEPROP 2 LAST SEC_TYPE 0402
J 0
(-7225 4175);
DISPLAY 1.021277 (-7225 4175);
PAINT ORANGE (-7225 4175);
DISPLAY INVISIBLE (-7225 4175);
FORCEPROP 0 LAST SEC 1
J 0
(-7225 4075);
DISPLAY 0.680851 (-7225 4075);
PAINT MONO (-7225 4075);
DISPLAY INVISIBLE (-7225 4075);
FORCEPROP 2 LAST ROOM BMC_MISC
J 0
(-7225 4075);
DISPLAY 1.021277 (-7225 4075);
PAINT ORANGE (-7225 4075);
DISPLAY INVISIBLE (-7225 4075);
FORCEPROP 2 LAST CDS_LIB mstr_discrete
J 0
(-7175 3975);
PAINT ORANGE (-7175 3975);
DISPLAY INVISIBLE (-7175 3975);
FORCEPROP 2 LAST CDS_LOCATION R2T29
J 0
(-7225 4025);
DISPLAY 0.617021 (-7225 4025);
PAINT AQUA (-7225 4025);
DISPLAY INVISIBLE (-7225 4025);
FORCEADD OFFPAGE..2
(-5950 3975);
FORCEPROP 2 LAST $XR2 146 
J 0
(-5521 3975);
DISPLAY 0.638298 (-5521 3975);
PAINT MONO (-5521 3975);
FORCEPROP 2 LAST $XR1 119 
J 0
(-5641 3975);
DISPLAY 0.638298 (-5641 3975);
PAINT MONO (-5641 3975);
FORCEPROP 2 LAST $XR0 108 
J 0
(-5761 3975);
DISPLAY 0.638298 (-5761 3975);
PAINT MONO (-5761 3975);
FORCEPROP 1 LAST OFFPAGE TRUE
J 0
(-5625 3850);
DISPLAY 0.872340 (-5625 3850);
PAINT GREEN (-5625 3850);
DISPLAY INVISIBLE (-5625 3850);
FORCEPROP 2 LAST PATH I299
J 0
(-5775 4050);
DISPLAY 1.021277 (-5775 4050);
PAINT ORANGE (-5775 4050);
DISPLAY INVISIBLE (-5775 4050);
FORCEPROP 1 LAST COMMENT_BODY TRUE
J 0
(-5995 3880);
DISPLAY 0.872340 (-5995 3880);
PAINT GREEN (-5995 3880);
DISPLAY INVISIBLE (-5995 3880);
FORCEPROP 2 LAST CDS_LIB mstr_standard
J 0
(-5950 3975);
PAINT ORANGE (-5950 3975);
DISPLAY INVISIBLE (-5950 3975);
FORCEADD OFFPAGE..2
(-1250 3825);
FORCEPROP 2 LAST $XR1 146 
J 0
(-941 3825);
DISPLAY 0.638298 (-941 3825);
PAINT MONO (-941 3825);
FORCEPROP 2 LAST $XR0 120 
J 0
(-1061 3825);
DISPLAY 0.638298 (-1061 3825);
PAINT MONO (-1061 3825);
FORCEPROP 1 LAST OFFPAGE TRUE
J 0
(-925 3700);
DISPLAY 0.872340 (-925 3700);
PAINT GREEN (-925 3700);
DISPLAY INVISIBLE (-925 3700);
FORCEPROP 2 LAST PATH I300
J 0
(-1200 3900);
DISPLAY 1.021277 (-1200 3900);
PAINT ORANGE (-1200 3900);
DISPLAY INVISIBLE (-1200 3900);
FORCEPROP 2 LAST CDS_LIB mstr_standard
J 0
(-1250 3825);
PAINT ORANGE (-1250 3825);
DISPLAY INVISIBLE (-1250 3825);
FORCEPROP 1 LAST COMMENT_BODY TRUE
J 0
(-1295 3730);
DISPLAY 0.872340 (-1295 3730);
PAINT GREEN (-1295 3730);
DISPLAY INVISIBLE (-1295 3730);
FORCEADD OFFPAGE..1
(-2900 3825);
FORCEPROP 2 LAST $XR0 120 
J 0
(-3152 3825);
DISPLAY 0.638298 (-3152 3825);
PAINT MONO (-3152 3825);
FORCEPROP 1 LAST COMMENT_BODY TRUE
J 0
(-2775 3725);
DISPLAY 0.872340 (-2775 3725);
PAINT GREEN (-2775 3725);
DISPLAY INVISIBLE (-2775 3725);
FORCEPROP 1 LAST OFFPAGE TRUE
J 0
(-2575 3700);
DISPLAY 0.872340 (-2575 3700);
PAINT GREEN (-2575 3700);
DISPLAY INVISIBLE (-2575 3700);
FORCEPROP 2 LAST PATH I301
J 0
(-2850 3900);
DISPLAY 1.021277 (-2850 3900);
PAINT ORANGE (-2850 3900);
DISPLAY INVISIBLE (-2850 3900);
FORCEPROP 2 LAST CDS_LIB mstr_standard
J 0
(-2900 3825);
PAINT ORANGE (-2900 3825);
DISPLAY INVISIBLE (-2900 3825);
FORCEADD RES..1
(-2050 3825);
FORCEPROP 1 LAST PACK_TYPE 0402
J 0
(-1750 3775);
DISPLAY 0.617021 (-1750 3775);
PAINT SKYBLUE (-1750 3775);
FORCEPROP 1 LAST WATTAGE 1/16W
J 2
(-1775 3775);
DISPLAY 0.617021 (-1775 3775);
PAINT SKYBLUE (-1775 3775);
FORCEPROP 1 LASTPIN (-1950 3825) $PN 2
J 0
(-1988 3837);
DISPLAY 0.617021 (-1988 3837);
PAINT ORANGE (-1988 3837);
FORCEPROP 1 LAST TOLERANCE 1.0%
J 0
(-2000 3775);
DISPLAY 0.617021 (-2000 3775);
PAINT SKYBLUE (-2000 3775);
FORCEPROP 1 LAST MATERIAL CHIP
J 0
(-1975 3725);
DISPLAY 0.617021 (-1975 3725);
PAINT SKYBLUE (-1975 3725);
FORCEPROP 1 LAST LOCATION R2N25
J 0
(-2100 3875);
DISPLAY 0.617021 (-2100 3875);
PAINT AQUA (-2100 3875);
FORCEPROP 1 LAST PART_NUMBER G21796-208
J 0
(-2275 3725);
DISPLAY 0.617021 (-2275 3725);
PAINT BLUE (-2275 3725);
FORCEPROP 1 LAST VALUE 51.1
J 2
(-2075 3775);
DISPLAY 0.617021 (-2075 3775);
PAINT SKYBLUE (-2075 3775);
FORCEPROP 1 LASTPIN (-2150 3825) $PN 1
J 0
(-2138 3837);
DISPLAY 0.617021 (-2138 3837);
PAINT ORANGE (-2138 3837);
FORCEPROP 0 LAST BOM_COST SM_CONTROLLER
J 0
(-2100 4125);
DISPLAY 1.021277 (-2100 4125);
PAINT ORANGE (-2100 4125);
DISPLAY INVISIBLE (-2100 4125);
FORCEPROP 0 LAST ROOM BMC_MISC
J 0
(-2100 4025);
DISPLAY 1.021277 (-2100 4025);
PAINT ORANGE (-2100 4025);
DISPLAY INVISIBLE (-2100 4025);
FORCEPROP 1 LAST PATH I302
J 0
(-2100 3975);
DISPLAY 0.978723 (-2100 3975);
PAINT WHITE (-2100 3975);
DISPLAY INVISIBLE (-2100 3975);
FORCEPROP 2 LAST CDS_LOCATION R2N25
J 0
(-2100 3875);
DISPLAY 0.617021 (-2100 3875);
PAINT AQUA (-2100 3875);
DISPLAY INVISIBLE (-2100 3875);
FORCEPROP 2 LAST SEC 1
J 0
(-2100 4025);
DISPLAY 0.680851 (-2100 4025);
PAINT MONO (-2100 4025);
DISPLAY INVISIBLE (-2100 4025);
FORCEPROP 2 LAST SEC_TYPE 0402
J 0
(-2100 4025);
DISPLAY 1.021277 (-2100 4025);
PAINT ORANGE (-2100 4025);
DISPLAY INVISIBLE (-2100 4025);
FORCEPROP 2 LAST CDS_LIB mstr_discrete
J 0
(-2050 3825);
PAINT ORANGE (-2050 3825);
DISPLAY INVISIBLE (-2050 3825);
FORCEADD P3V3..1
(-1850 4275);
FORCEPROP 3 LASTPIN (-1850 4225) SIG_NAME P3V3\g
J 0
(-1840 4235);
DISPLAY 0.659574 (-1840 4235);
PAINT MONO (-1840 4235);
DISPLAY INVISIBLE (-1840 4235);
FORCEPROP 1 LAST BODY_TYPE PLUMBING
J 0
(-1895 4232);
DISPLAY 0.340426 (-1895 4232);
PAINT GREEN (-1895 4232);
DISPLAY INVISIBLE (-1895 4232);
FORCEPROP 2 LAST CDS_LIB mstr_symbols
J 0
(-1850 4275);
PAINT ORANGE (-1850 4275);
DISPLAY INVISIBLE (-1850 4275);
FORCEPROP 1 LAST SIZE 1B
J 0
(-1805 4297);
DISPLAY 0.340426 (-1805 4297);
PAINT GREEN (-1805 4297);
DISPLAY INVISIBLE (-1805 4297);
FORCEPROP 1 LAST VOLTAGE 3.3V
J 0
(-1895 4232);
DISPLAY 0.340426 (-1895 4232);
PAINT SKYBLUE (-1895 4232);
DISPLAY INVISIBLE (-1895 4232);
FORCEPROP 1 LAST PATH I303
J 0
(-1805 4277);
DISPLAY 0.340426 (-1805 4277);
PAINT GREEN (-1805 4277);
DISPLAY INVISIBLE (-1805 4277);
FORCEPROP 1 LAST HDL_POWER P3V3
J 0
(-2175 4150);
DISPLAY 0.872340 (-2175 4150);
PAINT ORANGE (-2175 4150);
DISPLAY INVISIBLE (-2175 4150);
FORCEADD RES..1
(-7175 3725);
FORCEPROP 1 LAST WATTAGE 1/16W
J 2
(-6750 3675);
DISPLAY 0.617021 (-6750 3675);
PAINT SKYBLUE (-6750 3675);
FORCEPROP 1 LAST MATERIAL CHIP
J 0
(-6925 3625);
DISPLAY 0.617021 (-6925 3625);
PAINT SKYBLUE (-6925 3625);
FORCEPROP 1 LAST PACK_TYPE 0402
J 0
(-7000 3675);
DISPLAY 0.617021 (-7000 3675);
PAINT SKYBLUE (-7000 3675);
FORCEPROP 1 LASTPIN (-7075 3725) $PN 2
J 0
(-7113 3737);
DISPLAY 0.617021 (-7113 3737);
PAINT ORANGE (-7113 3737);
FORCEPROP 1 LAST TOLERANCE 1%
J 0
(-7125 3675);
DISPLAY 0.617021 (-7125 3675);
PAINT SKYBLUE (-7125 3675);
FORCEPROP 1 LAST LOCATION R8F24
J 0
(-7225 3775);
DISPLAY 0.617021 (-7225 3775);
PAINT AQUA (-7225 3775);
FORCEPROP 1 LAST PART_NUMBER G21796-072
J 0
(-7400 3625);
DISPLAY 0.617021 (-7400 3625);
PAINT BLUE (-7400 3625);
FORCEPROP 1 LAST VALUE 4.75K
J 2
(-7200 3675);
DISPLAY 0.617021 (-7200 3675);
PAINT SKYBLUE (-7200 3675);
FORCEPROP 1 LASTPIN (-7275 3725) $PN 1
J 0
(-7263 3737);
DISPLAY 0.617021 (-7263 3737);
PAINT ORANGE (-7263 3737);
FORCEPROP 2 LAST BOM_COST SM_CONTROLLER
J 0
(-7225 3875);
DISPLAY 1.021277 (-7225 3875);
PAINT ORANGE (-7225 3875);
DISPLAY INVISIBLE (-7225 3875);
FORCEPROP 1 LAST PATH I316
J 0
(-7225 3875);
DISPLAY 0.978723 (-7225 3875);
PAINT WHITE (-7225 3875);
DISPLAY INVISIBLE (-7225 3875);
FORCEPROP 2 LAST SEC 1
J 0
(-7225 3925);
PAINT MONO (-7225 3925);
DISPLAY INVISIBLE (-7225 3925);
FORCEPROP 2 LAST SEC_TYPE 0402
J 0
(-7225 3925);
DISPLAY 1.021277 (-7225 3925);
PAINT ORANGE (-7225 3925);
DISPLAY INVISIBLE (-7225 3925);
FORCEPROP 2 LAST ROOM BMC_MISC
J 0
(-7225 3825);
DISPLAY 1.021277 (-7225 3825);
PAINT ORANGE (-7225 3825);
DISPLAY INVISIBLE (-7225 3825);
FORCEPROP 2 LAST CDS_LIB mstr_discrete
J 0
(-7175 3725);
PAINT ORANGE (-7175 3725);
DISPLAY INVISIBLE (-7175 3725);
FORCEPROP 2 LAST CDS_LOCATION R8F24
J 0
(-7225 3775);
DISPLAY 0.617021 (-7225 3775);
PAINT AQUA (-7225 3775);
DISPLAY INVISIBLE (-7225 3775);
FORCEADD OFFPAGE..2
(-5950 3725);
FORCEPROP 2 LAST $XR2 145 
J 0
(-5521 3725);
DISPLAY 0.638298 (-5521 3725);
PAINT MONO (-5521 3725);
FORCEPROP 2 LAST $XR1 119 
J 0
(-5641 3725);
DISPLAY 0.638298 (-5641 3725);
PAINT MONO (-5641 3725);
FORCEPROP 2 LAST $XR0 157 
J 0
(-5761 3725);
DISPLAY 0.638298 (-5761 3725);
PAINT MONO (-5761 3725);
FORCEPROP 1 LAST OFFPAGE TRUE
J 0
(-5625 3600);
DISPLAY 0.872340 (-5625 3600);
PAINT GREEN (-5625 3600);
DISPLAY INVISIBLE (-5625 3600);
FORCEPROP 2 LAST PATH I317
J 0
(-5900 3800);
DISPLAY 1.021277 (-5900 3800);
PAINT ORANGE (-5900 3800);
DISPLAY INVISIBLE (-5900 3800);
FORCEPROP 2 LAST CDS_LIB mstr_standard
J 0
(-5950 3725);
PAINT ORANGE (-5950 3725);
DISPLAY INVISIBLE (-5950 3725);
FORCEPROP 1 LAST COMMENT_BODY TRUE
J 0
(-5995 3630);
DISPLAY 0.872340 (-5995 3630);
PAINT GREEN (-5995 3630);
DISPLAY INVISIBLE (-5995 3630);
FORCEADD GND..1
(-6225 525);
FORCEPROP 3 LASTPIN (-6225 575) SIG_NAME GND\g
J 0
(-6215 585);
DISPLAY 0.659574 (-6215 585);
PAINT MONO (-6215 585);
DISPLAY INVISIBLE (-6215 585);
FORCEPROP 1 LAST HDL_POWER GND
J 0
(-6225 675);
DISPLAY 0.872340 (-6225 675);
PAINT GREEN (-6225 675);
DISPLAY INVISIBLE (-6225 675);
FORCEPROP 2 LAST CDS_LIB mstr_symbols
J 0
(-6225 525);
PAINT MONO (-6225 525);
DISPLAY INVISIBLE (-6225 525);
FORCEPROP 1 LAST PATH I322
J 0
(-6150 525);
DISPLAY 0.872340 (-6150 525);
PAINT AQUA (-6150 525);
DISPLAY INVISIBLE (-6150 525);
FORCEPROP 1 LAST VOLTAGE 0.0V
J 0
(-6270 482);
DISPLAY 0.340426 (-6270 482);
PAINT SKYBLUE (-6270 482);
DISPLAY INVISIBLE (-6270 482);
FORCEPROP 1 LAST SIZE 1B
J 0
(-6150 475);
DISPLAY 0.872340 (-6150 475);
PAINT AQUA (-6150 475);
DISPLAY INVISIBLE (-6150 475);
FORCEPROP 1 LAST BODY_TYPE PLUMBING
J 0
(-6270 482);
DISPLAY 0.340426 (-6270 482);
PAINT GREEN (-6270 482);
DISPLAY INVISIBLE (-6270 482);
FORCEADD OFFPAGE..1
(-7575 775);
FORCEPROP 2 LAST $XR1 97 
J 0
(-7886 775);
DISPLAY 0.638298 (-7886 775);
PAINT MONO (-7886 775);
FORCEPROP 2 LAST $XR0 21 
J 0
(-7796 775);
DISPLAY 0.638298 (-7796 775);
PAINT MONO (-7796 775);
FORCEPROP 2 LAST PATH I324
J 0
(-7525 850);
DISPLAY 1.021277 (-7525 850);
PAINT ORANGE (-7525 850);
DISPLAY INVISIBLE (-7525 850);
FORCEPROP 1 LAST COMMENT_BODY TRUE
J 0
(-7450 675);
DISPLAY 0.872340 (-7450 675);
PAINT GREEN (-7450 675);
DISPLAY INVISIBLE (-7450 675);
FORCEPROP 1 LAST OFFPAGE TRUE
J 0
(-7250 650);
DISPLAY 0.872340 (-7250 650);
PAINT GREEN (-7250 650);
DISPLAY INVISIBLE (-7250 650);
FORCEPROP 2 LAST CDS_LIB mstr_standard
J 0
(-7575 775);
PAINT MONO (-7575 775);
DISPLAY INVISIBLE (-7575 775);
FORCEADD OFFPAGE..2
(-4850 1425);
FORCEPROP 2 LAST $XR1 147 
J 0
(-4541 1425);
DISPLAY 0.638298 (-4541 1425);
PAINT MONO (-4541 1425);
FORCEPROP 2 LAST $XR0 119 
J 0
(-4661 1425);
DISPLAY 0.638298 (-4661 1425);
PAINT MONO (-4661 1425);
FORCEPROP 1 LAST OFFPAGE TRUE
J 0
(-4525 1300);
DISPLAY 0.872340 (-4525 1300);
PAINT GREEN (-4525 1300);
DISPLAY INVISIBLE (-4525 1300);
FORCEPROP 2 LAST PATH I325
J 0
(-4800 1500);
DISPLAY 1.021277 (-4800 1500);
PAINT ORANGE (-4800 1500);
DISPLAY INVISIBLE (-4800 1500);
FORCEPROP 2 LAST CDS_LIB mstr_standard
J 0
(-4850 1425);
PAINT MONO (-4850 1425);
DISPLAY INVISIBLE (-4850 1425);
FORCEPROP 1 LAST COMMENT_BODY TRUE
J 0
(-4895 1330);
DISPLAY 0.872340 (-4895 1330);
PAINT GREEN (-4895 1330);
DISPLAY INVISIBLE (-4895 1330);
FORCEADD RES..2
(-6225 1250);
FORCEPROP 1 LAST LOCATION R2T5
J 0
(-6180 1375);
DISPLAY 0.617021 (-6180 1375);
PAINT AQUA (-6180 1375);
FORCEPROP 1 LAST PART_NUMBER G21796-026
J 0
(-6185 1125);
DISPLAY 0.617021 (-6185 1125);
PAINT BLUE (-6185 1125);
FORCEPROP 1 LAST VALUE 1.00K
J 0
(-6180 1325);
DISPLAY 0.617021 (-6180 1325);
PAINT SKYBLUE (-6180 1325);
FORCEPROP 1 LAST TOLERANCE 1%
J 0
(-6180 1275);
DISPLAY 0.617021 (-6180 1275);
PAINT SKYBLUE (-6180 1275);
FORCEPROP 1 LAST PACK_TYPE 0402
J 0
(-6185 1075);
DISPLAY 0.617021 (-6185 1075);
PAINT SKYBLUE (-6185 1075);
FORCEPROP 1 LAST MATERIAL CHIP
J 0
(-6185 1175);
DISPLAY 0.617021 (-6185 1175);
PAINT SKYBLUE (-6185 1175);
FORCEPROP 1 LAST WATTAGE 1/16W
J 0
(-6185 1225);
DISPLAY 0.617021 (-6185 1225);
PAINT SKYBLUE (-6185 1225);
FORCEPROP 1 LASTPIN (-6225 1350) $PN 1
J 0
(-6220 1312);
DISPLAY 0.617021 (-6220 1312);
PAINT ORANGE (-6220 1312);
FORCEPROP 1 LASTPIN (-6225 1150) $PN 2
J 0
(-6220 1160);
DISPLAY 0.617021 (-6220 1160);
PAINT ORANGE (-6220 1160);
FORCEPROP 0 LAST BOM_COST PROC_SIDEBAND
J 0
(-6175 1575);
DISPLAY 1.021277 (-6175 1575);
PAINT ORANGE (-6175 1575);
DISPLAY INVISIBLE (-6175 1575);
FORCEPROP 2 LAST SEC_TYPE 0402
J 0
(-6175 1475);
DISPLAY 1.021277 (-6175 1475);
PAINT ORANGE (-6175 1475);
DISPLAY INVISIBLE (-6175 1475);
FORCEPROP 2 LAST SEC 1
J 0
(-6175 1475);
DISPLAY 0.680851 (-6175 1475);
PAINT MONO (-6175 1475);
DISPLAY INVISIBLE (-6175 1475);
FORCEPROP 1 LAST PATH I326
J 0
(-6175 1425);
DISPLAY 0.978723 (-6175 1425);
PAINT WHITE (-6175 1425);
DISPLAY INVISIBLE (-6175 1425);
FORCEPROP 0 LAST ROOM PROC_SIDEBAND
J 0
(-6175 1475);
DISPLAY 1.021277 (-6175 1475);
PAINT ORANGE (-6175 1475);
DISPLAY INVISIBLE (-6175 1475);
FORCEPROP 2 LAST CDS_LOCATION R2T5
J 0
(-6180 1375);
DISPLAY 0.617021 (-6180 1375);
PAINT AQUA (-6180 1375);
DISPLAY INVISIBLE (-6180 1375);
FORCEPROP 2 LAST CDS_LIB mstr_discrete
J 0
(-6225 1250);
PAINT MONO (-6225 1250);
DISPLAY INVISIBLE (-6225 1250);
FORCEADD RES..2
(-5575 1650);
FORCEPROP 1 LAST LOCATION R2T7
J 0
(-5530 1775);
DISPLAY 0.617021 (-5530 1775);
PAINT AQUA (-5530 1775);
FORCEPROP 1 LAST VALUE 1.00K
J 0
(-5530 1725);
DISPLAY 0.617021 (-5530 1725);
PAINT SKYBLUE (-5530 1725);
FORCEPROP 1 LAST WATTAGE 1/16W
J 0
(-5535 1625);
DISPLAY 0.617021 (-5535 1625);
PAINT SKYBLUE (-5535 1625);
FORCEPROP 1 LAST MATERIAL CHIP
J 0
(-5535 1575);
DISPLAY 0.617021 (-5535 1575);
PAINT SKYBLUE (-5535 1575);
FORCEPROP 1 LAST TOLERANCE 1%
J 0
(-5530 1675);
DISPLAY 0.617021 (-5530 1675);
PAINT SKYBLUE (-5530 1675);
FORCEPROP 1 LASTPIN (-5575 1750) $PN 1
J 0
(-5570 1712);
DISPLAY 0.617021 (-5570 1712);
PAINT ORANGE (-5570 1712);
FORCEPROP 1 LASTPIN (-5575 1550) $PN 2
J 0
(-5570 1560);
DISPLAY 0.617021 (-5570 1560);
PAINT ORANGE (-5570 1560);
FORCEPROP 1 LAST PART_NUMBER G21796-026
J 0
(-5535 1525);
DISPLAY 0.617021 (-5535 1525);
PAINT BLUE (-5535 1525);
FORCEPROP 1 LAST PACK_TYPE 0402
J 0
(-5535 1475);
DISPLAY 0.617021 (-5535 1475);
PAINT SKYBLUE (-5535 1475);
FORCEPROP 0 LAST BOM_COST PROC_SIDEBAND
J 0
(-5525 1975);
DISPLAY 1.021277 (-5525 1975);
PAINT ORANGE (-5525 1975);
DISPLAY INVISIBLE (-5525 1975);
FORCEPROP 2 LAST SEC_TYPE 0402
J 0
(-5525 1875);
DISPLAY 1.021277 (-5525 1875);
PAINT ORANGE (-5525 1875);
DISPLAY INVISIBLE (-5525 1875);
FORCEPROP 2 LAST SEC 1
J 0
(-5525 1875);
DISPLAY 0.680851 (-5525 1875);
PAINT MONO (-5525 1875);
DISPLAY INVISIBLE (-5525 1875);
FORCEPROP 1 LAST PATH I327
J 0
(-5525 1825);
DISPLAY 0.978723 (-5525 1825);
PAINT WHITE (-5525 1825);
DISPLAY INVISIBLE (-5525 1825);
FORCEPROP 0 LAST ROOM PROC_SIDEBAND
J 0
(-5525 1875);
DISPLAY 1.021277 (-5525 1875);
PAINT ORANGE (-5525 1875);
DISPLAY INVISIBLE (-5525 1875);
FORCEPROP 2 LAST CDS_LOCATION R2T7
J 0
(-5530 1775);
DISPLAY 0.617021 (-5530 1775);
PAINT AQUA (-5530 1775);
DISPLAY INVISIBLE (-5530 1775);
FORCEPROP 2 LAST CDS_LIB mstr_discrete
J 0
(-5575 1650);
PAINT MONO (-5575 1650);
DISPLAY INVISIBLE (-5575 1650);
FORCEADD P3V3_STBY..1
(-6225 1450);
FORCEPROP 3 LASTPIN (-6225 1400) SIG_NAME P3V3_STBY\g
J 0
(-6215 1410);
DISPLAY 0.659574 (-6215 1410);
PAINT MONO (-6215 1410);
DISPLAY INVISIBLE (-6215 1410);
FORCEPROP 2 LAST CDS_LIB mstr_symbols
J 0
(-6225 1450);
PAINT MONO (-6225 1450);
DISPLAY INVISIBLE (-6225 1450);
FORCEPROP 1 LAST SIZE 1B
J 0
(-6180 1472);
DISPLAY 0.340426 (-6180 1472);
PAINT GREEN (-6180 1472);
DISPLAY INVISIBLE (-6180 1472);
FORCEPROP 1 LAST PATH I328
J 0
(-6180 1452);
DISPLAY 0.340426 (-6180 1452);
PAINT GREEN (-6180 1452);
DISPLAY INVISIBLE (-6180 1452);
FORCEPROP 1 LAST VOLTAGE 3.3V
J 0
(-6270 1407);
DISPLAY 0.340426 (-6270 1407);
PAINT SKYBLUE (-6270 1407);
DISPLAY INVISIBLE (-6270 1407);
FORCEPROP 1 LAST BODY_TYPE PLUMBING
J 0
(-6270 1407);
DISPLAY 0.340426 (-6270 1407);
PAINT GREEN (-6270 1407);
DISPLAY INVISIBLE (-6270 1407);
FORCEPROP 1 LAST HDL_POWER P3V3_STBY
J 0
(-6525 1325);
DISPLAY 0.872340 (-6525 1325);
PAINT ORANGE (-6525 1325);
DISPLAY INVISIBLE (-6525 1325);
FORCEADD P3V3_STBY..1
(-5575 1875);
FORCEPROP 3 LASTPIN (-5575 1825) SIG_NAME P3V3_STBY\g
J 0
(-5565 1835);
DISPLAY 0.659574 (-5565 1835);
PAINT MONO (-5565 1835);
DISPLAY INVISIBLE (-5565 1835);
FORCEPROP 1 LAST VOLTAGE 3.3V
J 0
(-5620 1832);
DISPLAY 0.340426 (-5620 1832);
PAINT SKYBLUE (-5620 1832);
DISPLAY INVISIBLE (-5620 1832);
FORCEPROP 2 LAST CDS_LIB mstr_symbols
J 0
(-5575 1875);
PAINT MONO (-5575 1875);
DISPLAY INVISIBLE (-5575 1875);
FORCEPROP 1 LAST SIZE 1B
J 0
(-5530 1897);
DISPLAY 0.340426 (-5530 1897);
PAINT GREEN (-5530 1897);
DISPLAY INVISIBLE (-5530 1897);
FORCEPROP 1 LAST BODY_TYPE PLUMBING
J 0
(-5620 1832);
DISPLAY 0.340426 (-5620 1832);
PAINT GREEN (-5620 1832);
DISPLAY INVISIBLE (-5620 1832);
FORCEPROP 1 LAST PATH I329
J 0
(-5530 1877);
DISPLAY 0.340426 (-5530 1877);
PAINT GREEN (-5530 1877);
DISPLAY INVISIBLE (-5530 1877);
FORCEPROP 1 LAST HDL_POWER P3V3_STBY
J 0
(-5875 1750);
DISPLAY 0.872340 (-5875 1750);
PAINT ORANGE (-5875 1750);
DISPLAY INVISIBLE (-5875 1750);
FORCEADD NPN..1
(-6275 775);
FORCEPROP 1 LAST LOCATION Q2T1
J 0
(-6125 825);
DISPLAY 0.617021 (-6125 825);
PAINT AQUA (-6125 825);
FORCEPROP 1 LAST PART_NUMBER C52245-001
J 0
(-6125 625);
DISPLAY 0.617021 (-6125 625);
PAINT BLUE (-6125 625);
FORCEPROP 1 LAST VALUE MMBT3904
J 0
(-6125 775);
DISPLAY 0.617021 (-6125 775);
PAINT SKYBLUE (-6125 775);
FORCEPROP 1 LAST PACK_TYPE SM
J 0
(-6125 675);
DISPLAY 0.617021 (-6125 675);
PAINT SKYBLUE (-6125 675);
FORCEPROP 1 LAST MATERIAL IC
J 0
(-6125 725);
DISPLAY 0.617021 (-6125 725);
PAINT SKYBLUE (-6125 725);
FORCEPROP 1 LASTPIN (-6225 875) $PN 3
J 0
(-6206 885);
DISPLAY 0.617021 (-6206 885);
PAINT GREEN (-6206 885);
FORCEPROP 1 LASTPIN (-6225 675) $PN 2
J 0
(-6200 625);
DISPLAY 0.617021 (-6200 625);
PAINT GREEN (-6200 625);
FORCEPROP 1 LASTPIN (-6375 775) $PN 1
J 0
(-6405 850);
DISPLAY 0.617021 (-6405 850);
PAINT GREEN (-6405 850);
FORCEPROP 0 LAST BOM_COST PROC_SIDEBAND
J 0
(-6125 1025);
DISPLAY 1.021277 (-6125 1025);
PAINT ORANGE (-6125 1025);
DISPLAY INVISIBLE (-6125 1025);
FORCEPROP 2 LAST SEC_TYPE SM
J 0
(-6125 925);
DISPLAY 1.021277 (-6125 925);
PAINT ORANGE (-6125 925);
DISPLAY INVISIBLE (-6125 925);
FORCEPROP 2 LAST SEC 1
J 0
(-6125 925);
DISPLAY 0.680851 (-6125 925);
PAINT MONO (-6125 925);
DISPLAY INVISIBLE (-6125 925);
FORCEPROP 2 LAST CDS_LOCATION Q2T1
J 0
(-6125 825);
DISPLAY 0.617021 (-6125 825);
PAINT AQUA (-6125 825);
DISPLAY INVISIBLE (-6125 825);
FORCEPROP 1 LAST PATH I330
J 0
(-6125 875);
DISPLAY 0.978723 (-6125 875);
PAINT BLUE (-6125 875);
DISPLAY INVISIBLE (-6125 875);
FORCEPROP 0 LAST ROOM PROC_SIDEBAND
J 0
(-6125 925);
DISPLAY 1.021277 (-6125 925);
PAINT ORANGE (-6125 925);
DISPLAY INVISIBLE (-6125 925);
FORCEPROP 2 LAST CDS_LIB mstr_discrete
J 0
(-6275 775);
PAINT MONO (-6275 775);
DISPLAY INVISIBLE (-6275 775);
FORCEADD GND..1
(-5575 775);
FORCEPROP 3 LASTPIN (-5575 825) SIG_NAME GND\g
J 0
(-5565 835);
DISPLAY 0.659574 (-5565 835);
PAINT MONO (-5565 835);
DISPLAY INVISIBLE (-5565 835);
FORCEPROP 1 LAST PATH I333
J 0
(-5500 775);
DISPLAY 0.872340 (-5500 775);
PAINT AQUA (-5500 775);
DISPLAY INVISIBLE (-5500 775);
FORCEPROP 2 LAST CDS_LIB mstr_symbols
J 0
(-5575 775);
PAINT MONO (-5575 775);
DISPLAY INVISIBLE (-5575 775);
FORCEPROP 1 LAST HDL_POWER GND
J 0
(-5575 925);
DISPLAY 0.872340 (-5575 925);
PAINT GREEN (-5575 925);
DISPLAY INVISIBLE (-5575 925);
FORCEPROP 1 LAST VOLTAGE 0.0V
J 0
(-5620 732);
DISPLAY 0.340426 (-5620 732);
PAINT SKYBLUE (-5620 732);
DISPLAY INVISIBLE (-5620 732);
FORCEPROP 1 LAST SIZE 1B
J 0
(-5500 725);
DISPLAY 0.872340 (-5500 725);
PAINT AQUA (-5500 725);
DISPLAY INVISIBLE (-5500 725);
FORCEPROP 1 LAST BODY_TYPE PLUMBING
J 0
(-5620 732);
DISPLAY 0.340426 (-5620 732);
PAINT GREEN (-5620 732);
DISPLAY INVISIBLE (-5620 732);
FORCEADD RES..2
(-2275 1525);
FORCEPROP 1 LAST PART_NUMBER G21796-072
J 0
(-2235 1400);
DISPLAY 0.617021 (-2235 1400);
PAINT BLUE (-2235 1400);
FORCEPROP 1 LAST LOCATION R8D25
J 0
(-2230 1650);
DISPLAY 0.617021 (-2230 1650);
PAINT AQUA (-2230 1650);
FORCEPROP 1 LAST TOLERANCE 1%
J 0
(-2230 1550);
DISPLAY 0.617021 (-2230 1550);
PAINT SKYBLUE (-2230 1550);
FORCEPROP 1 LAST VALUE 4.75K
J 0
(-2230 1600);
DISPLAY 0.617021 (-2230 1600);
PAINT SKYBLUE (-2230 1600);
FORCEPROP 1 LASTPIN (-2275 1625) $PN 1
J 0
(-2270 1587);
DISPLAY 0.617021 (-2270 1587);
PAINT ORANGE (-2270 1587);
FORCEPROP 1 LAST PACK_TYPE 0402
J 0
(-2235 1350);
DISPLAY 0.617021 (-2235 1350);
PAINT SKYBLUE (-2235 1350);
FORCEPROP 1 LAST MATERIAL CHIP
J 0
(-2235 1450);
DISPLAY 0.617021 (-2235 1450);
PAINT SKYBLUE (-2235 1450);
FORCEPROP 1 LAST WATTAGE 1/16W
J 0
(-2235 1500);
DISPLAY 0.617021 (-2235 1500);
PAINT SKYBLUE (-2235 1500);
FORCEPROP 1 LASTPIN (-2275 1425) $PN 2
J 0
(-2270 1435);
DISPLAY 0.617021 (-2270 1435);
PAINT ORANGE (-2270 1435);
FORCEPROP 0 LAST BOM_COST SM_CONTROLLER
J 0
(-2225 1850);
DISPLAY 1.021277 (-2225 1850);
PAINT ORANGE (-2225 1850);
DISPLAY INVISIBLE (-2225 1850);
FORCEPROP 0 LAST ROOM BMC_MISC
J 0
(-2225 1750);
DISPLAY 1.021277 (-2225 1750);
PAINT ORANGE (-2225 1750);
DISPLAY INVISIBLE (-2225 1750);
FORCEPROP 2 LAST SEC_TYPE 0402
J 0
(-2225 1750);
DISPLAY 1.021277 (-2225 1750);
PAINT ORANGE (-2225 1750);
DISPLAY INVISIBLE (-2225 1750);
FORCEPROP 1 LAST PATH I335
J 0
(-2225 1700);
DISPLAY 0.978723 (-2225 1700);
PAINT WHITE (-2225 1700);
DISPLAY INVISIBLE (-2225 1700);
FORCEPROP 2 LAST SEC 1
J 0
(-2225 1750);
DISPLAY 0.680851 (-2225 1750);
PAINT MONO (-2225 1750);
DISPLAY INVISIBLE (-2225 1750);
FORCEPROP 2 LAST CDS_LOCATION R8D25
J 0
(-2230 1650);
DISPLAY 0.617021 (-2230 1650);
PAINT AQUA (-2230 1650);
DISPLAY INVISIBLE (-2230 1650);
FORCEPROP 2 LAST CDS_LIB mstr_discrete
J 0
(-2275 1525);
PAINT ORANGE (-2275 1525);
DISPLAY INVISIBLE (-2275 1525);
FORCEADD P3V3_STBY..1
(-2275 1725);
FORCEPROP 3 LASTPIN (-2275 1675) SIG_NAME P3V3_STBY\g
J 0
(-2265 1685);
DISPLAY 0.659574 (-2265 1685);
PAINT MONO (-2265 1685);
DISPLAY INVISIBLE (-2265 1685);
FORCEPROP 1 LAST SIZE 1B
J 0
(-2230 1747);
DISPLAY 0.340426 (-2230 1747);
PAINT GREEN (-2230 1747);
DISPLAY INVISIBLE (-2230 1747);
FORCEPROP 2 LAST CDS_LIB mstr_symbols
J 0
(-2275 1725);
PAINT MONO (-2275 1725);
DISPLAY INVISIBLE (-2275 1725);
FORCEPROP 1 LAST PATH I339
J 0
(-2230 1727);
DISPLAY 0.340426 (-2230 1727);
PAINT GREEN (-2230 1727);
DISPLAY INVISIBLE (-2230 1727);
FORCEPROP 1 LAST BODY_TYPE PLUMBING
J 0
(-2320 1682);
DISPLAY 0.340426 (-2320 1682);
PAINT GREEN (-2320 1682);
DISPLAY INVISIBLE (-2320 1682);
FORCEPROP 1 LAST VOLTAGE 3.3V
J 0
(-2320 1682);
DISPLAY 0.340426 (-2320 1682);
PAINT SKYBLUE (-2320 1682);
DISPLAY INVISIBLE (-2320 1682);
FORCEPROP 1 LAST HDL_POWER P3V3_STBY
J 0
(-2575 1600);
DISPLAY 0.872340 (-2575 1600);
PAINT ORANGE (-2575 1600);
DISPLAY INVISIBLE (-2575 1600);
FORCEADD FET_N..8
(-5575 1100);
FORCEPROP 1 LAST PART_NUMBER C79254-001
J 0
(-5375 900);
DISPLAY 0.617021 (-5375 900);
PAINT BLUE (-5375 900);
FORCEPROP 1 LAST LOCATION Q2T2
J 0
(-5375 1100);
DISPLAY 0.617021 (-5375 1100);
PAINT AQUA (-5375 1100);
FORCEPROP 1 LAST VALUE 2N7002
J 0
(-5375 1050);
DISPLAY 0.617021 (-5375 1050);
PAINT SKYBLUE (-5375 1050);
FORCEPROP 1 LASTPIN (-5575 1300) $PN 3
J 2
(-5522 1265);
DISPLAY 0.617021 (-5522 1265);
PAINT WHITE (-5522 1265);
FORCEPROP 1 LAST MATERIAL FET
J 0
(-5375 1000);
DISPLAY 0.617021 (-5375 1000);
PAINT SKYBLUE (-5375 1000);
FORCEPROP 1 LASTPIN (-5775 1000) $PN 1
J 2
(-5772 1015);
DISPLAY 0.617021 (-5772 1015);
PAINT WHITE (-5772 1015);
FORCEPROP 1 LASTPIN (-5575 900) $PN 2
J 2
(-5517 900);
DISPLAY 0.617021 (-5517 900);
PAINT WHITE (-5517 900);
FORCEPROP 2 LAST SEC_TYPE SOT23LF
J 0
(-5375 1200);
DISPLAY 1.021277 (-5375 1200);
PAINT ORANGE (-5375 1200);
DISPLAY INVISIBLE (-5375 1200);
FORCEPROP 0 LAST BOM_COST PROC_SIDEBAND
J 0
(-5375 1300);
DISPLAY 1.021277 (-5375 1300);
PAINT ORANGE (-5375 1300);
DISPLAY INVISIBLE (-5375 1300);
FORCEPROP 2 LAST SEC 1
J 0
(-5375 1200);
DISPLAY 0.680851 (-5375 1200);
PAINT MONO (-5375 1200);
DISPLAY INVISIBLE (-5375 1200);
FORCEPROP 2 LAST CDS_LOCATION Q2T2
J 0
(-5375 1100);
DISPLAY 0.617021 (-5375 1100);
PAINT AQUA (-5375 1100);
DISPLAY INVISIBLE (-5375 1100);
FORCEPROP 1 LAST PATH I340
J 0
(-5375 1150);
DISPLAY 0.978723 (-5375 1150);
PAINT BLUE (-5375 1150);
DISPLAY INVISIBLE (-5375 1150);
FORCEPROP 0 LAST ROOM PROC_SIDEBAND
J 0
(-5375 1200);
DISPLAY 1.021277 (-5375 1200);
PAINT ORANGE (-5375 1200);
DISPLAY INVISIBLE (-5375 1200);
FORCEPROP 2 LAST CDS_LIB mstr_discrete
J 0
(-5575 1100);
PAINT MONO (-5575 1100);
DISPLAY INVISIBLE (-5575 1100);
FORCEPROP 1 LAST PACK_TYPE SOT23LF
J 0
(-5375 950);
DISPLAY 0.978723 (-5375 950);
PAINT SKYBLUE (-5375 950);
DISPLAY INVISIBLE (-5375 950);
FORCEADD RES..1
(-7175 3100);
FORCEPROP 1 LASTPIN (-7075 3100) $PN 2
J 0
(-7113 3112);
DISPLAY 0.617021 (-7113 3112);
PAINT ORANGE (-7113 3112);
FORCEPROP 1 LAST TOLERANCE 1%
J 0
(-7125 3050);
DISPLAY 0.617021 (-7125 3050);
PAINT SKYBLUE (-7125 3050);
FORCEPROP 1 LAST PACK_TYPE 0402
J 0
(-7000 3050);
DISPLAY 0.617021 (-7000 3050);
PAINT SKYBLUE (-7000 3050);
FORCEPROP 1 LAST WATTAGE 1/16W
J 2
(-6750 3050);
DISPLAY 0.617021 (-6750 3050);
PAINT SKYBLUE (-6750 3050);
FORCEPROP 1 LAST MATERIAL CHIP
J 0
(-6925 3000);
DISPLAY 0.617021 (-6925 3000);
PAINT SKYBLUE (-6925 3000);
FORCEPROP 1 LAST LOCATION R3N12
J 0
(-7225 3150);
DISPLAY 0.617021 (-7225 3150);
PAINT AQUA (-7225 3150);
FORCEPROP 1 LAST PART_NUMBER G21796-072
J 0
(-7400 3000);
DISPLAY 0.617021 (-7400 3000);
PAINT BLUE (-7400 3000);
FORCEPROP 1 LASTPIN (-7275 3100) $PN 1
J 0
(-7263 3112);
DISPLAY 0.617021 (-7263 3112);
PAINT ORANGE (-7263 3112);
FORCEPROP 1 LAST VALUE 4.75K
J 2
(-7200 3050);
DISPLAY 0.617021 (-7200 3050);
PAINT SKYBLUE (-7200 3050);
FORCEPROP 2 LAST SEC_TYPE 0402
J 0
(-7225 3300);
DISPLAY 1.021277 (-7225 3300);
PAINT ORANGE (-7225 3300);
DISPLAY INVISIBLE (-7225 3300);
FORCEPROP 2 LAST SEC 1
J 0
(-7225 3300);
PAINT MONO (-7225 3300);
DISPLAY INVISIBLE (-7225 3300);
FORCEPROP 2 LAST BOM_COST SM_CONTROLLER
J 0
(-7225 3250);
DISPLAY 1.021277 (-7225 3250);
PAINT ORANGE (-7225 3250);
DISPLAY INVISIBLE (-7225 3250);
FORCEPROP 2 LAST CDS_LIB mstr_discrete
J 0
(-7175 3100);
PAINT ORANGE (-7175 3100);
DISPLAY INVISIBLE (-7175 3100);
FORCEPROP 2 LAST CDS_LOCATION R3N12
J 0
(-7225 3150);
DISPLAY 0.617021 (-7225 3150);
PAINT AQUA (-7225 3150);
DISPLAY INVISIBLE (-7225 3150);
FORCEPROP 1 LAST PATH I342
J 0
(-7225 3250);
DISPLAY 0.978723 (-7225 3250);
PAINT WHITE (-7225 3250);
DISPLAY INVISIBLE (-7225 3250);
FORCEPROP 2 LAST ROOM BMC_MISC
J 0
(-7225 3200);
DISPLAY 1.021277 (-7225 3200);
PAINT ORANGE (-7225 3200);
DISPLAY INVISIBLE (-7225 3200);
FORCEADD OFFPAGE..2
(-5950 3100);
FORCEPROP 2 LAST $XR3 190 
J 0
(-5401 3100);
DISPLAY 0.638298 (-5401 3100);
PAINT MONO (-5401 3100);
FORCEPROP 2 LAST $XR2 144 
J 0
(-5521 3100);
DISPLAY 0.638298 (-5521 3100);
PAINT MONO (-5521 3100);
FORCEPROP 2 LAST $XR1 120 
J 0
(-5641 3100);
DISPLAY 0.638298 (-5641 3100);
PAINT MONO (-5641 3100);
FORCEPROP 2 LAST $XR0 181 
J 0
(-5761 3100);
DISPLAY 0.638298 (-5761 3100);
PAINT MONO (-5761 3100);
FORCEPROP 2 LAST PATH I343
J 0
(-5775 3175);
DISPLAY 1.021277 (-5775 3175);
PAINT ORANGE (-5775 3175);
DISPLAY INVISIBLE (-5775 3175);
FORCEPROP 2 LAST CDS_LIB mstr_standard
J 0
(-5950 3100);
PAINT MONO (-5950 3100);
DISPLAY INVISIBLE (-5950 3100);
FORCEPROP 1 LAST OFFPAGE TRUE
J 0
(-5625 2975);
DISPLAY 0.872340 (-5625 2975);
PAINT GREEN (-5625 2975);
DISPLAY INVISIBLE (-5625 2975);
FORCEPROP 1 LAST COMMENT_BODY TRUE
J 0
(-5995 3005);
DISPLAY 0.872340 (-5995 3005);
PAINT GREEN (-5995 3005);
DISPLAY INVISIBLE (-5995 3005);
FORCEADD RES..1
(-7175 2875);
FORCEPROP 1 LAST WATTAGE 1/16W
J 2
(-6750 2825);
DISPLAY 0.617021 (-6750 2825);
PAINT SKYBLUE (-6750 2825);
FORCEPROP 1 LAST MATERIAL CHIP
J 0
(-6925 2775);
DISPLAY 0.617021 (-6925 2775);
PAINT SKYBLUE (-6925 2775);
FORCEPROP 1 LAST PACK_TYPE 0402
J 0
(-7000 2825);
DISPLAY 0.617021 (-7000 2825);
PAINT SKYBLUE (-7000 2825);
FORCEPROP 1 LASTPIN (-7075 2875) $PN 2
J 0
(-7113 2887);
DISPLAY 0.617021 (-7113 2887);
PAINT ORANGE (-7113 2887);
FORCEPROP 1 LAST TOLERANCE 1%
J 0
(-7125 2825);
DISPLAY 0.617021 (-7125 2825);
PAINT SKYBLUE (-7125 2825);
FORCEPROP 1 LAST LOCATION R3N11
J 0
(-7225 2925);
DISPLAY 0.617021 (-7225 2925);
PAINT AQUA (-7225 2925);
FORCEPROP 1 LAST PART_NUMBER G21796-072
J 0
(-7400 2775);
DISPLAY 0.617021 (-7400 2775);
PAINT BLUE (-7400 2775);
FORCEPROP 1 LAST VALUE 4.75K
J 2
(-7200 2825);
DISPLAY 0.617021 (-7200 2825);
PAINT SKYBLUE (-7200 2825);
FORCEPROP 1 LASTPIN (-7275 2875) $PN 1
J 0
(-7263 2887);
DISPLAY 0.617021 (-7263 2887);
PAINT ORANGE (-7263 2887);
FORCEPROP 2 LAST SEC_TYPE 0402
J 0
(-7225 3075);
DISPLAY 1.021277 (-7225 3075);
PAINT ORANGE (-7225 3075);
DISPLAY INVISIBLE (-7225 3075);
FORCEPROP 2 LAST SEC 1
J 0
(-7225 3075);
PAINT MONO (-7225 3075);
DISPLAY INVISIBLE (-7225 3075);
FORCEPROP 2 LAST CDS_LIB mstr_discrete
J 0
(-7175 2875);
PAINT ORANGE (-7175 2875);
DISPLAY INVISIBLE (-7175 2875);
FORCEPROP 2 LAST BOM_COST SM_CONTROLLER
J 0
(-7225 3025);
DISPLAY 1.021277 (-7225 3025);
PAINT ORANGE (-7225 3025);
DISPLAY INVISIBLE (-7225 3025);
FORCEPROP 2 LAST CDS_LOCATION R3N11
J 0
(-7225 2925);
DISPLAY 0.617021 (-7225 2925);
PAINT AQUA (-7225 2925);
DISPLAY INVISIBLE (-7225 2925);
FORCEPROP 1 LAST PATH I344
J 0
(-7225 3025);
DISPLAY 0.978723 (-7225 3025);
PAINT WHITE (-7225 3025);
DISPLAY INVISIBLE (-7225 3025);
FORCEPROP 2 LAST ROOM BMC_MISC
J 0
(-7225 2975);
DISPLAY 1.021277 (-7225 2975);
PAINT ORANGE (-7225 2975);
DISPLAY INVISIBLE (-7225 2975);
FORCEADD OFFPAGE..2
(-5950 2875);
FORCEPROP 2 LAST $XR2 120 
J 0
(-5521 2875);
DISPLAY 0.638298 (-5521 2875);
PAINT MONO (-5521 2875);
FORCEPROP 2 LAST $XR1 181 
J 0
(-5641 2875);
DISPLAY 0.638298 (-5641 2875);
PAINT MONO (-5641 2875);
FORCEPROP 2 LAST $XR0 147 
J 0
(-5761 2875);
DISPLAY 0.638298 (-5761 2875);
PAINT MONO (-5761 2875);
FORCEPROP 1 LAST OFFPAGE TRUE
J 0
(-5625 2750);
DISPLAY 0.872340 (-5625 2750);
PAINT GREEN (-5625 2750);
DISPLAY INVISIBLE (-5625 2750);
FORCEPROP 2 LAST PATH I345
J 0
(-5775 2950);
DISPLAY 1.021277 (-5775 2950);
PAINT ORANGE (-5775 2950);
DISPLAY INVISIBLE (-5775 2950);
FORCEPROP 2 LAST CDS_LIB mstr_standard
J 0
(-5950 2875);
PAINT MONO (-5950 2875);
DISPLAY INVISIBLE (-5950 2875);
FORCEPROP 1 LAST COMMENT_BODY TRUE
J 0
(-5995 2780);
DISPLAY 0.872340 (-5995 2780);
PAINT GREEN (-5995 2780);
DISPLAY INVISIBLE (-5995 2780);
FORCEADD RES..1
(-7175 2650);
FORCEPROP 1 LAST WATTAGE 1/16W
J 2
(-6750 2600);
DISPLAY 0.617021 (-6750 2600);
PAINT SKYBLUE (-6750 2600);
FORCEPROP 1 LAST PACK_TYPE 0402
J 0
(-7000 2600);
DISPLAY 0.617021 (-7000 2600);
PAINT SKYBLUE (-7000 2600);
FORCEPROP 1 LASTPIN (-7075 2650) $PN 2
J 0
(-7113 2662);
DISPLAY 0.617021 (-7113 2662);
PAINT ORANGE (-7113 2662);
FORCEPROP 1 LAST TOLERANCE 1%
J 0
(-7125 2600);
DISPLAY 0.617021 (-7125 2600);
PAINT SKYBLUE (-7125 2600);
FORCEPROP 1 LAST MATERIAL CHIP
J 0
(-6925 2550);
DISPLAY 0.617021 (-6925 2550);
PAINT SKYBLUE (-6925 2550);
FORCEPROP 1 LAST LOCATION R2M2
J 0
(-7225 2700);
DISPLAY 0.617021 (-7225 2700);
PAINT AQUA (-7225 2700);
FORCEPROP 1 LAST PART_NUMBER G21796-072
J 0
(-7400 2550);
DISPLAY 0.617021 (-7400 2550);
PAINT BLUE (-7400 2550);
FORCEPROP 1 LAST VALUE 4.75K
J 2
(-7200 2600);
DISPLAY 0.617021 (-7200 2600);
PAINT SKYBLUE (-7200 2600);
FORCEPROP 1 LASTPIN (-7275 2650) $PN 1
J 0
(-7263 2662);
DISPLAY 0.617021 (-7263 2662);
PAINT ORANGE (-7263 2662);
FORCEPROP 2 LAST SEC_TYPE 0402
J 0
(-7225 2850);
DISPLAY 1.021277 (-7225 2850);
PAINT ORANGE (-7225 2850);
DISPLAY INVISIBLE (-7225 2850);
FORCEPROP 2 LAST SEC 1
J 0
(-7225 2850);
PAINT MONO (-7225 2850);
DISPLAY INVISIBLE (-7225 2850);
FORCEPROP 2 LAST BOM_COST SM_CONTROLLER
J 0
(-7225 2800);
DISPLAY 1.021277 (-7225 2800);
PAINT ORANGE (-7225 2800);
DISPLAY INVISIBLE (-7225 2800);
FORCEPROP 1 LAST PATH I346
J 0
(-7225 2800);
DISPLAY 0.978723 (-7225 2800);
PAINT WHITE (-7225 2800);
DISPLAY INVISIBLE (-7225 2800);
FORCEPROP 2 LAST CDS_LIB mstr_discrete
J 0
(-7175 2650);
PAINT ORANGE (-7175 2650);
DISPLAY INVISIBLE (-7175 2650);
FORCEPROP 2 LAST CDS_LOCATION R2M2
J 0
(-7225 2700);
DISPLAY 0.617021 (-7225 2700);
PAINT AQUA (-7225 2700);
DISPLAY INVISIBLE (-7225 2700);
FORCEPROP 2 LAST ROOM BMC_MISC
J 0
(-7225 2750);
DISPLAY 1.021277 (-7225 2750);
PAINT ORANGE (-7225 2750);
DISPLAY INVISIBLE (-7225 2750);
FORCEADD OFFPAGE..2
(-5950 2650);
FORCEPROP 2 LAST $XR3 120 
J 0
(-5431 2650);
DISPLAY 0.638298 (-5431 2650);
PAINT MONO (-5431 2650);
FORCEPROP 2 LAST $XR2 191 
J 0
(-5551 2650);
DISPLAY 0.638298 (-5551 2650);
PAINT MONO (-5551 2650);
FORCEPROP 2 LAST $XR1 156 
J 0
(-5671 2650);
DISPLAY 0.638298 (-5671 2650);
PAINT MONO (-5671 2650);
FORCEPROP 2 LAST $XR0 89 
J 0
(-5761 2650);
DISPLAY 0.638298 (-5761 2650);
PAINT MONO (-5761 2650);
FORCEPROP 2 LAST PATH I347
J 0
(-5500 2700);
DISPLAY 1.021277 (-5500 2700);
PAINT ORANGE (-5500 2700);
DISPLAY INVISIBLE (-5500 2700);
FORCEPROP 1 LAST OFFPAGE TRUE
J 0
(-5625 2525);
DISPLAY 0.872340 (-5625 2525);
PAINT GREEN (-5625 2525);
DISPLAY INVISIBLE (-5625 2525);
FORCEPROP 2 LAST CDS_LIB mstr_standard
J 0
(-5950 2650);
PAINT MONO (-5950 2650);
DISPLAY INVISIBLE (-5950 2650);
FORCEPROP 1 LAST COMMENT_BODY TRUE
J 0
(-5995 2555);
DISPLAY 0.872340 (-5995 2555);
PAINT GREEN (-5995 2555);
DISPLAY INVISIBLE (-5995 2555);
FORCEADD RES..1
(-7175 2425);
FORCEPROP 1 LAST WATTAGE 1/16W
J 2
(-6750 2375);
DISPLAY 0.617021 (-6750 2375);
PAINT SKYBLUE (-6750 2375);
FORCEPROP 1 LAST PACK_TYPE 0402
J 0
(-7000 2375);
DISPLAY 0.617021 (-7000 2375);
PAINT SKYBLUE (-7000 2375);
FORCEPROP 1 LAST MATERIAL CHIP
J 0
(-6925 2325);
DISPLAY 0.617021 (-6925 2325);
PAINT SKYBLUE (-6925 2325);
FORCEPROP 1 LAST TOLERANCE 1%
J 0
(-7125 2375);
DISPLAY 0.617021 (-7125 2375);
PAINT SKYBLUE (-7125 2375);
FORCEPROP 1 LASTPIN (-7075 2425) $PN 2
J 0
(-7113 2437);
DISPLAY 0.617021 (-7113 2437);
PAINT ORANGE (-7113 2437);
FORCEPROP 1 LAST LOCATION R2M5
J 0
(-7225 2475);
DISPLAY 0.617021 (-7225 2475);
PAINT AQUA (-7225 2475);
FORCEPROP 1 LAST PART_NUMBER G21796-072
J 0
(-7400 2325);
DISPLAY 0.617021 (-7400 2325);
PAINT BLUE (-7400 2325);
FORCEPROP 1 LAST VALUE 4.75K
J 2
(-7200 2375);
DISPLAY 0.617021 (-7200 2375);
PAINT SKYBLUE (-7200 2375);
FORCEPROP 1 LASTPIN (-7275 2425) $PN 1
J 0
(-7263 2437);
DISPLAY 0.617021 (-7263 2437);
PAINT ORANGE (-7263 2437);
FORCEPROP 2 LAST SEC 1
J 0
(-7225 2625);
PAINT MONO (-7225 2625);
DISPLAY INVISIBLE (-7225 2625);
FORCEPROP 1 LAST PATH I348
J 0
(-7225 2575);
DISPLAY 0.978723 (-7225 2575);
PAINT WHITE (-7225 2575);
DISPLAY INVISIBLE (-7225 2575);
FORCEPROP 2 LAST SEC_TYPE 0402
J 0
(-7225 2625);
DISPLAY 1.021277 (-7225 2625);
PAINT ORANGE (-7225 2625);
DISPLAY INVISIBLE (-7225 2625);
FORCEPROP 2 LAST BOM_COST SM_CONTROLLER
J 0
(-7225 2575);
DISPLAY 1.021277 (-7225 2575);
PAINT ORANGE (-7225 2575);
DISPLAY INVISIBLE (-7225 2575);
FORCEPROP 2 LAST ROOM BMC_MISC
J 0
(-7225 2525);
DISPLAY 1.021277 (-7225 2525);
PAINT ORANGE (-7225 2525);
DISPLAY INVISIBLE (-7225 2525);
FORCEPROP 2 LAST CDS_LIB mstr_discrete
J 0
(-7175 2425);
PAINT ORANGE (-7175 2425);
DISPLAY INVISIBLE (-7175 2425);
FORCEPROP 2 LAST CDS_LOCATION R2M5
J 0
(-7225 2475);
DISPLAY 0.617021 (-7225 2475);
PAINT AQUA (-7225 2475);
DISPLAY INVISIBLE (-7225 2475);
FORCEADD OFFPAGE..2
(-5950 2425);
FORCEPROP 2 LAST $XR2 190 
J 0
(-5521 2425);
DISPLAY 0.638298 (-5521 2425);
PAINT MONO (-5521 2425);
FORCEPROP 2 LAST $XR1 144 
J 0
(-5641 2425);
DISPLAY 0.638298 (-5641 2425);
PAINT MONO (-5641 2425);
FORCEPROP 2 LAST $XR0 119 
J 0
(-5761 2425);
DISPLAY 0.638298 (-5761 2425);
PAINT MONO (-5761 2425);
FORCEPROP 2 LAST PATH I349
J 0
(-5325 2475);
DISPLAY 1.021277 (-5325 2475);
PAINT ORANGE (-5325 2475);
DISPLAY INVISIBLE (-5325 2475);
FORCEPROP 1 LAST OFFPAGE TRUE
J 0
(-5625 2300);
DISPLAY 0.872340 (-5625 2300);
PAINT GREEN (-5625 2300);
DISPLAY INVISIBLE (-5625 2300);
FORCEPROP 1 LAST COMMENT_BODY TRUE
J 0
(-5995 2330);
DISPLAY 0.872340 (-5995 2330);
PAINT GREEN (-5995 2330);
DISPLAY INVISIBLE (-5995 2330);
FORCEPROP 2 LAST CDS_LIB mstr_standard
J 0
(-5950 2425);
PAINT MONO (-5950 2425);
DISPLAY INVISIBLE (-5950 2425);
FORCEADD SWITCH_D90553001..1
(-4375 2375);
FORCEPROP 1 LAST PART_NAME SWITCH_D90553001
J 0
(-4625 2225);
DISPLAY 0.744681 (-4625 2225);
PAINT GREEN (-4625 2225);
FORCEPROP 1 LAST LOCATION S8E1
J 0
(-4475 2625);
DISPLAY 0.617021 (-4475 2625);
PAINT AQUA (-4475 2625);
FORCEPROP 1 LAST MATERIAL IC
J 0
(-4475 2575);
DISPLAY 0.617021 (-4475 2575);
PAINT SKYBLUE (-4475 2575);
FORCEPROP 1 LASTPIN (-4125 2375) $PN 2
J 0
(-4200 2388);
DISPLAY 0.617021 (-4200 2388);
PAINT ORANGE (-4200 2388);
FORCEPROP 1 LASTPIN (-4625 2375) $PN 1
J 0
(-4588 2388);
DISPLAY 0.617021 (-4588 2388);
PAINT ORANGE (-4588 2388);
FORCEPROP 1 LAST PART_NUMBER D90553-001
J 0
(-4625 2275);
DISPLAY 0.617021 (-4625 2275);
PAINT BLUE (-4625 2275);
FORCEPROP 1 LAST PACK_TYPE SMLF
J 0
(-4475 2675);
DISPLAY 0.744681 (-4475 2675);
PAINT SKYBLUE (-4475 2675);
DISPLAY INVISIBLE (-4475 2675);
FORCEPROP 0 LAST BOM_COST MIO_CHASSIS
J 0
(-4475 2825);
DISPLAY 1.021277 (-4475 2825);
PAINT ORANGE (-4475 2825);
DISPLAY INVISIBLE (-4475 2825);
FORCEPROP 2 LAST SEC_TYPE SMLF
J 0
(-4475 2675);
DISPLAY 1.021277 (-4475 2675);
PAINT ORANGE (-4475 2675);
DISPLAY INVISIBLE (-4475 2675);
FORCEPROP 2 LAST SEC 1
J 0
(-4475 2675);
DISPLAY 0.680851 (-4475 2675);
PAINT MONO (-4475 2675);
DISPLAY INVISIBLE (-4475 2675);
FORCEPROP 2 LAST CDS_LOCATION S8E1
J 0
(-4475 2625);
DISPLAY 0.617021 (-4475 2625);
PAINT AQUA (-4475 2625);
DISPLAY INVISIBLE (-4475 2625);
FORCEPROP 0 LAST ROOM MIO_CHASSIS
J 0
(-4475 2725);
DISPLAY 1.021277 (-4475 2725);
PAINT ORANGE (-4475 2725);
DISPLAY INVISIBLE (-4475 2725);
FORCEPROP 1 LAST PATH I351
J 0
(-4275 2575);
DISPLAY 0.744681 (-4275 2575);
PAINT GREEN (-4275 2575);
DISPLAY INVISIBLE (-4275 2575);
FORCEPROP 2 LAST CDS_LIB mstr_misc
J 0
(-4375 2375);
PAINT MONO (-4375 2375);
DISPLAY INVISIBLE (-4375 2375);
FORCEADD RES..1
(-3650 2375);
FORCEPROP 1 LAST PACK_TYPE 0402
J 0
(-3400 2225);
DISPLAY 0.617021 (-3400 2225);
PAINT SKYBLUE (-3400 2225);
FORCEPROP 1 LAST LOCATION R2R9
J 0
(-3700 2425);
DISPLAY 0.617021 (-3700 2425);
PAINT AQUA (-3700 2425);
FORCEPROP 1 LAST PART_NUMBER G21796-004
J 0
(-3700 2475);
DISPLAY 0.617021 (-3700 2475);
PAINT BLUE (-3700 2475);
FORCEPROP 1 LAST MATERIAL CHIP
J 0
(-3650 2225);
DISPLAY 0.617021 (-3650 2225);
PAINT SKYBLUE (-3650 2225);
FORCEPROP 1 LASTPIN (-3550 2375) $PN 2
J 0
(-3588 2387);
DISPLAY 0.617021 (-3588 2387);
PAINT ORANGE (-3588 2387);
FORCEPROP 1 LASTPIN (-3750 2375) $PN 1
J 0
(-3738 2387);
DISPLAY 0.617021 (-3738 2387);
PAINT ORANGE (-3738 2387);
FORCEPROP 1 LAST WATTAGE 1/16W
J 2
(-3675 2225);
DISPLAY 0.617021 (-3675 2225);
PAINT SKYBLUE (-3675 2225);
FORCEPROP 1 LAST TOLERANCE 1%
J 0
(-3650 2275);
DISPLAY 0.617021 (-3650 2275);
PAINT SKYBLUE (-3650 2275);
FORCEPROP 1 LAST VALUE 200.0
J 2
(-3675 2275);
DISPLAY 0.617021 (-3675 2275);
PAINT SKYBLUE (-3675 2275);
FORCEPROP 2 LAST SEC_TYPE 0402
J 0
(-3700 2575);
DISPLAY 1.021277 (-3700 2575);
PAINT ORANGE (-3700 2575);
DISPLAY INVISIBLE (-3700 2575);
FORCEPROP 0 LAST BOM_COST MIO_CHASSIS
J 0
(-3700 2675);
DISPLAY 1.021277 (-3700 2675);
PAINT ORANGE (-3700 2675);
DISPLAY INVISIBLE (-3700 2675);
FORCEPROP 2 LAST SEC 1
J 0
(-3700 2575);
DISPLAY 0.680851 (-3700 2575);
PAINT MONO (-3700 2575);
DISPLAY INVISIBLE (-3700 2575);
FORCEPROP 0 LAST ROOM MIO_CHASSIS
J 0
(-3700 2575);
DISPLAY 1.021277 (-3700 2575);
PAINT ORANGE (-3700 2575);
DISPLAY INVISIBLE (-3700 2575);
FORCEPROP 1 LAST PATH I352
J 0
(-3700 2525);
DISPLAY 0.978723 (-3700 2525);
PAINT WHITE (-3700 2525);
DISPLAY INVISIBLE (-3700 2525);
FORCEPROP 2 LAST CDS_LOCATION R2R9
J 0
(-3700 2425);
DISPLAY 0.617021 (-3700 2425);
PAINT AQUA (-3700 2425);
DISPLAY INVISIBLE (-3700 2425);
FORCEPROP 2 LAST CDS_LIB mstr_discrete
J 0
(-3650 2375);
PAINT MONO (-3650 2375);
DISPLAY INVISIBLE (-3650 2375);
FORCEADD CAP_A..1
(-3200 2150);
FORCEPROP 1 LAST LOCATION C2R12
J 0
(-3150 2250);
DISPLAY 0.617021 (-3150 2250);
PAINT AQUA (-3150 2250);
FORCEPROP 1 LAST VALUE 1.0UF
J 0
(-3150 2200);
DISPLAY 0.617021 (-3150 2200);
PAINT SKYBLUE (-3150 2200);
FORCEPROP 1 LAST TOLERANCE 10%
J 0
(-3150 2100);
DISPLAY 0.617021 (-3150 2100);
PAINT SKYBLUE (-3150 2100);
FORCEPROP 1 LAST VOLTAGE 6.3V
J 0
(-3150 2150);
DISPLAY 0.617021 (-3150 2150);
PAINT SKYBLUE (-3150 2150);
FORCEPROP 1 LAST MATERIAL X6S
J 0
(-3150 2050);
DISPLAY 0.617021 (-3150 2050);
PAINT SKYBLUE (-3150 2050);
FORCEPROP 1 LASTPIN (-3200 2250) $PN 1
J 0
(-3190 2230);
DISPLAY 0.617021 (-3190 2230);
PAINT ORANGE (-3190 2230);
FORCEPROP 1 LASTPIN (-3200 2050) $PN 2
J 0
(-3190 2030);
DISPLAY 0.617021 (-3190 2030);
PAINT ORANGE (-3190 2030);
FORCEPROP 1 LAST PART_NUMBER D97712-004
J 0
(-3150 2000);
DISPLAY 0.617021 (-3150 2000);
PAINT BLUE (-3150 2000);
FORCEPROP 1 LAST PACK_TYPE 0402V
J 0
(-3150 1950);
DISPLAY 0.617021 (-3150 1950);
PAINT SKYBLUE (-3150 1950);
FORCEPROP 0 LAST ROOM MIO_CHASSIS
J 0
(-3150 2350);
DISPLAY 1.021277 (-3150 2350);
PAINT ORANGE (-3150 2350);
DISPLAY INVISIBLE (-3150 2350);
FORCEPROP 2 LAST SEC 1
J 0
(-3150 2350);
DISPLAY 0.680851 (-3150 2350);
PAINT MONO (-3150 2350);
DISPLAY INVISIBLE (-3150 2350);
FORCEPROP 2 LAST SEC_TYPE 0402V
J 0
(-3150 2350);
DISPLAY 1.021277 (-3150 2350);
PAINT ORANGE (-3150 2350);
DISPLAY INVISIBLE (-3150 2350);
FORCEPROP 0 LAST BOM_COST MIO_CHASSIS
J 0
(-3150 2450);
DISPLAY 1.021277 (-3150 2450);
PAINT ORANGE (-3150 2450);
DISPLAY INVISIBLE (-3150 2450);
FORCEPROP 1 LAST PATH I353
J 0
(-3150 2300);
DISPLAY 0.978723 (-3150 2300);
PAINT WHITE (-3150 2300);
DISPLAY INVISIBLE (-3150 2300);
FORCEPROP 2 LAST CDS_SEC 1
J 0
(-3150 2300);
PAINT ORANGE (-3150 2300);
DISPLAY INVISIBLE (-3150 2300);
FORCEPROP 2 LAST CDS_LIB dev_discrete
J 0
(-3200 2150);
PAINT ORANGE (-3200 2150);
DISPLAY INVISIBLE (-3200 2150);
FORCEPROP 2 LAST CDS_LOCATION C2R12
J 0
(-3150 2250);
DISPLAY 0.617021 (-3150 2250);
PAINT AQUA (-3150 2250);
DISPLAY INVISIBLE (-3150 2250);
FORCEADD GND..1
(-3200 1875);
FORCEPROP 3 LASTPIN (-3200 1925) SIG_NAME GND\g
J 0
(-3190 1935);
DISPLAY 0.659574 (-3190 1935);
PAINT MONO (-3190 1935);
DISPLAY INVISIBLE (-3190 1935);
FORCEPROP 1 LAST HDL_POWER GND
J 0
(-3200 2025);
DISPLAY 0.872340 (-3200 2025);
PAINT GREEN (-3200 2025);
DISPLAY INVISIBLE (-3200 2025);
FORCEPROP 1 LAST VOLTAGE 0.0V
J 0
(-3245 1832);
DISPLAY 0.340426 (-3245 1832);
PAINT SKYBLUE (-3245 1832);
DISPLAY INVISIBLE (-3245 1832);
FORCEPROP 1 LAST SIZE 1B
J 0
(-3125 1825);
DISPLAY 0.872340 (-3125 1825);
PAINT AQUA (-3125 1825);
DISPLAY INVISIBLE (-3125 1825);
FORCEPROP 2 LAST CDS_LIB mstr_symbols
J 0
(-3200 1875);
PAINT MONO (-3200 1875);
DISPLAY INVISIBLE (-3200 1875);
FORCEPROP 1 LAST BODY_TYPE PLUMBING
J 0
(-3245 1832);
DISPLAY 0.340426 (-3245 1832);
PAINT GREEN (-3245 1832);
DISPLAY INVISIBLE (-3245 1832);
FORCEPROP 1 LAST PATH I354
J 0
(-3125 1875);
DISPLAY 0.872340 (-3125 1875);
PAINT AQUA (-3125 1875);
DISPLAY INVISIBLE (-3125 1875);
FORCEADD GND..1
(-4775 2200);
FORCEPROP 3 LASTPIN (-4775 2250) SIG_NAME GND\g
J 0
(-4765 2260);
DISPLAY 0.659574 (-4765 2260);
PAINT MONO (-4765 2260);
DISPLAY INVISIBLE (-4765 2260);
FORCEPROP 1 LAST HDL_POWER GND
J 0
(-4775 2350);
DISPLAY 0.872340 (-4775 2350);
PAINT GREEN (-4775 2350);
DISPLAY INVISIBLE (-4775 2350);
FORCEPROP 1 LAST PATH I355
J 0
(-4700 2200);
DISPLAY 0.872340 (-4700 2200);
PAINT AQUA (-4700 2200);
DISPLAY INVISIBLE (-4700 2200);
FORCEPROP 1 LAST BODY_TYPE PLUMBING
J 0
(-4820 2157);
DISPLAY 0.340426 (-4820 2157);
PAINT GREEN (-4820 2157);
DISPLAY INVISIBLE (-4820 2157);
FORCEPROP 1 LAST SIZE 1B
J 0
(-4700 2150);
DISPLAY 0.872340 (-4700 2150);
PAINT AQUA (-4700 2150);
DISPLAY INVISIBLE (-4700 2150);
FORCEPROP 2 LAST CDS_LIB mstr_symbols
J 0
(-4775 2200);
PAINT MONO (-4775 2200);
DISPLAY INVISIBLE (-4775 2200);
FORCEPROP 1 LAST VOLTAGE 0.0V
J 0
(-4820 2157);
DISPLAY 0.340426 (-4820 2157);
PAINT SKYBLUE (-4820 2157);
DISPLAY INVISIBLE (-4820 2157);
FORCEADD TTL2G14..1
(-2900 2375);
FORCEPROP 1 LAST POWER_GROUP VCC=P3V3_STBY;GND=GND
J 1
(-2550 2185);
DISPLAY 0.617021 (-2550 2185);
PAINT ORANGE (-2550 2185);
FORCEPROP 1 LAST LOCATION U2R1
J 0
(-2950 2575);
DISPLAY 0.617021 (-2950 2575);
PAINT AQUA (-2950 2575);
FORCEPROP 2 LASTPIN (-2750 2375) $PN 4
J 0
(-2740 2385);
DISPLAY 0.617021 (-2740 2385);
PAINT ORANGE (-2740 2385);
FORCEPROP 1 LAST PART_NUMBER D18476-001
J 0
(-2950 2240);
DISPLAY 0.617021 (-2950 2240);
PAINT BLUE (-2950 2240);
FORCEPROP 1 LAST VALUE 74LVC2G14
J 0
(-2950 2475);
DISPLAY 0.617021 (-2950 2475);
PAINT SKYBLUE (-2950 2475);
FORCEPROP 1 LAST MATERIAL IC
J 0
(-2950 2525);
DISPLAY 0.617021 (-2950 2525);
PAINT SKYBLUE (-2950 2525);
FORCEPROP 2 LASTPIN (-3000 2375) $PN 3
J 2
(-3010 2385);
DISPLAY 0.617021 (-3010 2385);
PAINT ORANGE (-3010 2385);
FORCEPROP 1 LAST PACK_TYPE SMLF
J 0
(-2950 2625);
DISPLAY 0.978723 (-2950 2625);
PAINT SKYBLUE (-2950 2625);
DISPLAY INVISIBLE (-2950 2625);
FORCEPROP 0 LAST BOM_COST MIO_CHASSIS
J 0
(-2950 2775);
DISPLAY 1.021277 (-2950 2775);
PAINT ORANGE (-2950 2775);
DISPLAY INVISIBLE (-2950 2775);
FORCEPROP 2 LAST SEC_TYPE SMLF
J 0
(-2950 2625);
DISPLAY 1.021277 (-2950 2625);
PAINT ORANGE (-2950 2625);
DISPLAY INVISIBLE (-2950 2625);
FORCEPROP 2 LAST SEC 2
J 0
(-2950 2625);
DISPLAY 0.680851 (-2950 2625);
PAINT MONO (-2950 2625);
DISPLAY INVISIBLE (-2950 2625);
FORCEPROP 2 LAST CDS_LOCATION U2R1
J 0
(-2950 2575);
DISPLAY 0.617021 (-2950 2575);
PAINT AQUA (-2950 2575);
DISPLAY INVISIBLE (-2950 2575);
FORCEPROP 0 LAST ROOM MIO_CHASSIS
J 0
(-2950 2675);
DISPLAY 1.021277 (-2950 2675);
PAINT ORANGE (-2950 2675);
DISPLAY INVISIBLE (-2950 2675);
FORCEPROP 2 LAST CDS_LIB mstr_ttl
J 0
(-2900 2375);
PAINT MONO (-2900 2375);
DISPLAY INVISIBLE (-2900 2375);
FORCEPROP 1 LAST PATH I356
J 0
(-2850 2425);
DISPLAY 0.978723 (-2850 2425);
PAINT WHITE (-2850 2425);
DISPLAY INVISIBLE (-2850 2425);
FORCEADD TTL2G14..1
(-2150 2375);
FORCEPROP 2 LASTPIN (-2000 2375) $PN 6
J 0
(-1990 2385);
DISPLAY 0.617021 (-1990 2385);
PAINT ORANGE (-1990 2385);
FORCEPROP 1 LAST POWER_GROUP VCC=P3V3_STBY;GND=GND
J 1
(-1800 2185);
DISPLAY 0.617021 (-1800 2185);
PAINT ORANGE (-1800 2185);
FORCEPROP 1 LAST PART_NUMBER D18476-001
J 0
(-2200 2240);
DISPLAY 0.617021 (-2200 2240);
PAINT BLUE (-2200 2240);
FORCEPROP 1 LAST VALUE 74LVC2G14
J 0
(-2200 2475);
DISPLAY 0.617021 (-2200 2475);
PAINT SKYBLUE (-2200 2475);
FORCEPROP 1 LAST LOCATION U2R1
J 0
(-2200 2575);
DISPLAY 0.617021 (-2200 2575);
PAINT AQUA (-2200 2575);
FORCEPROP 1 LAST MATERIAL IC
J 0
(-2200 2525);
DISPLAY 0.617021 (-2200 2525);
PAINT SKYBLUE (-2200 2525);
FORCEPROP 2 LASTPIN (-2250 2375) $PN 1
J 2
(-2260 2385);
DISPLAY 0.617021 (-2260 2385);
PAINT ORANGE (-2260 2385);
FORCEPROP 0 LAST ROOM MIO_CHASSIS
J 0
(-2200 2675);
DISPLAY 1.021277 (-2200 2675);
PAINT ORANGE (-2200 2675);
DISPLAY INVISIBLE (-2200 2675);
FORCEPROP 2 LAST CDS_LOCATION U2R1
J 0
(-2200 2575);
DISPLAY 0.617021 (-2200 2575);
PAINT AQUA (-2200 2575);
DISPLAY INVISIBLE (-2200 2575);
FORCEPROP 2 LAST SEC 1
J 0
(-2200 2625);
DISPLAY 0.680851 (-2200 2625);
PAINT MONO (-2200 2625);
DISPLAY INVISIBLE (-2200 2625);
FORCEPROP 2 LAST SEC_TYPE SMLF
J 0
(-2200 2625);
DISPLAY 1.021277 (-2200 2625);
PAINT ORANGE (-2200 2625);
DISPLAY INVISIBLE (-2200 2625);
FORCEPROP 1 LAST PACK_TYPE SMLF
J 0
(-2200 2625);
DISPLAY 0.978723 (-2200 2625);
PAINT SKYBLUE (-2200 2625);
DISPLAY INVISIBLE (-2200 2625);
FORCEPROP 0 LAST BOM_COST MIO_CHASSIS
J 0
(-2200 2775);
DISPLAY 1.021277 (-2200 2775);
PAINT ORANGE (-2200 2775);
DISPLAY INVISIBLE (-2200 2775);
FORCEPROP 1 LAST PATH I357
J 0
(-2100 2425);
DISPLAY 0.978723 (-2100 2425);
PAINT WHITE (-2100 2425);
DISPLAY INVISIBLE (-2100 2425);
FORCEPROP 2 LAST CDS_LIB mstr_ttl
J 0
(-2150 2375);
PAINT MONO (-2150 2375);
DISPLAY INVISIBLE (-2150 2375);
FORCEADD RES..1
(-1400 2375);
FORCEPROP 1 LAST PACK_TYPE 0402
J 0
(-1150 2225);
DISPLAY 0.617021 (-1150 2225);
PAINT SKYBLUE (-1150 2225);
FORCEPROP 1 LAST PART_NUMBER G21796-074
J 0
(-1450 2475);
DISPLAY 0.617021 (-1450 2475);
PAINT BLUE (-1450 2475);
FORCEPROP 1 LASTPIN (-1300 2375) $PN 2
J 0
(-1338 2387);
DISPLAY 0.617021 (-1338 2387);
PAINT ORANGE (-1338 2387);
FORCEPROP 1 LAST LOCATION R2R10
J 0
(-1450 2425);
DISPLAY 0.617021 (-1450 2425);
PAINT AQUA (-1450 2425);
FORCEPROP 1 LASTPIN (-1500 2375) $PN 1
J 0
(-1488 2387);
DISPLAY 0.617021 (-1488 2387);
PAINT ORANGE (-1488 2387);
FORCEPROP 1 LAST TOLERANCE 1%
J 0
(-1400 2275);
DISPLAY 0.617021 (-1400 2275);
PAINT SKYBLUE (-1400 2275);
FORCEPROP 1 LAST MATERIAL CHIP
J 0
(-1400 2225);
DISPLAY 0.617021 (-1400 2225);
PAINT SKYBLUE (-1400 2225);
FORCEPROP 1 LAST VALUE 33.2
J 2
(-1425 2275);
DISPLAY 0.617021 (-1425 2275);
PAINT SKYBLUE (-1425 2275);
FORCEPROP 1 LAST WATTAGE 1/16W
J 2
(-1425 2225);
DISPLAY 0.617021 (-1425 2225);
PAINT SKYBLUE (-1425 2225);
FORCEPROP 0 LAST ROOM MIO_CHASSIS
J 0
(-1450 2575);
DISPLAY 1.021277 (-1450 2575);
PAINT ORANGE (-1450 2575);
DISPLAY INVISIBLE (-1450 2575);
FORCEPROP 2 LAST SEC 1
J 0
(-1450 2575);
DISPLAY 0.680851 (-1450 2575);
PAINT MONO (-1450 2575);
DISPLAY INVISIBLE (-1450 2575);
FORCEPROP 0 LAST BOM_COST MIO_CHASSIS
J 0
(-1450 2675);
DISPLAY 1.021277 (-1450 2675);
PAINT ORANGE (-1450 2675);
DISPLAY INVISIBLE (-1450 2675);
FORCEPROP 2 LAST SEC_TYPE 0402
J 0
(-1450 2575);
DISPLAY 1.021277 (-1450 2575);
PAINT ORANGE (-1450 2575);
DISPLAY INVISIBLE (-1450 2575);
FORCEPROP 1 LAST PATH I358
J 0
(-1450 2525);
DISPLAY 0.978723 (-1450 2525);
PAINT WHITE (-1450 2525);
DISPLAY INVISIBLE (-1450 2525);
FORCEPROP 2 LAST CDS_LIB mstr_discrete
J 0
(-1400 2375);
PAINT MONO (-1400 2375);
DISPLAY INVISIBLE (-1400 2375);
FORCEPROP 2 LAST CDS_LOCATION R2R10
J 0
(-1450 2425);
DISPLAY 0.617021 (-1450 2425);
PAINT AQUA (-1450 2425);
DISPLAY INVISIBLE (-1450 2425);
FORCEADD OFFPAGE..2
(-825 2375);
FORCEPROP 2 LAST $XR2 145 
J 0
(-396 2375);
DISPLAY 0.638298 (-396 2375);
PAINT MONO (-396 2375);
FORCEPROP 2 LAST $XR1 119 
J 0
(-516 2375);
DISPLAY 0.638298 (-516 2375);
PAINT MONO (-516 2375);
FORCEPROP 2 LAST $XR0 157 
J 0
(-636 2375);
DISPLAY 0.638298 (-636 2375);
PAINT MONO (-636 2375);
FORCEPROP 1 LAST OFFPAGE TRUE
J 0
(-500 2250);
DISPLAY 0.872340 (-500 2250);
PAINT GREEN (-500 2250);
DISPLAY INVISIBLE (-500 2250);
FORCEPROP 2 LAST PATH I359
J 0
(-775 2450);
DISPLAY 1.021277 (-775 2450);
PAINT ORANGE (-775 2450);
DISPLAY INVISIBLE (-775 2450);
FORCEPROP 1 LAST COMMENT_BODY TRUE
J 0
(-870 2280);
DISPLAY 0.872340 (-870 2280);
PAINT GREEN (-870 2280);
DISPLAY INVISIBLE (-870 2280);
FORCEPROP 2 LAST CDS_LIB mstr_standard
J 0
(-825 2375);
PAINT MONO (-825 2375);
DISPLAY INVISIBLE (-825 2375);
FORCEADD OFFPAGE..2
(-5950 2200);
FORCEPROP 2 LAST $XR2 145 
J 0
(-5521 2200);
DISPLAY 0.638298 (-5521 2200);
PAINT MONO (-5521 2200);
FORCEPROP 2 LAST $XR1 136 
J 0
(-5641 2200);
DISPLAY 0.638298 (-5641 2200);
PAINT MONO (-5641 2200);
FORCEPROP 2 LAST $XR0 120 
J 0
(-5761 2200);
DISPLAY 0.638298 (-5761 2200);
PAINT MONO (-5761 2200);
FORCEPROP 2 LAST PATH I360
J 0
(-5500 2250);
DISPLAY 1.021277 (-5500 2250);
PAINT ORANGE (-5500 2250);
DISPLAY INVISIBLE (-5500 2250);
FORCEPROP 1 LAST OFFPAGE TRUE
J 0
(-5625 2075);
DISPLAY 0.872340 (-5625 2075);
PAINT GREEN (-5625 2075);
DISPLAY INVISIBLE (-5625 2075);
FORCEPROP 2 LAST CDS_LIB mstr_standard
J 0
(-5950 2200);
PAINT MONO (-5950 2200);
DISPLAY INVISIBLE (-5950 2200);
FORCEPROP 1 LAST COMMENT_BODY TRUE
J 0
(-5995 2105);
DISPLAY 0.872340 (-5995 2105);
PAINT GREEN (-5995 2105);
DISPLAY INVISIBLE (-5995 2105);
FORCEADD RES..1
(-7175 2200);
FORCEPROP 1 LAST WATTAGE 1/16W
J 2
(-6750 2150);
DISPLAY 0.617021 (-6750 2150);
PAINT SKYBLUE (-6750 2150);
FORCEPROP 1 LAST MATERIAL EMPTY
J 0
(-6925 2100);
DISPLAY 0.617021 (-6925 2100);
PAINT RED (-6925 2100);
FORCEPROP 1 LAST PACK_TYPE 0402
J 0
(-7000 2150);
DISPLAY 0.617021 (-7000 2150);
PAINT SKYBLUE (-7000 2150);
FORCEPROP 1 LASTPIN (-7075 2200) $PN 2
J 0
(-7113 2212);
DISPLAY 0.617021 (-7113 2212);
PAINT ORANGE (-7113 2212);
FORCEPROP 1 LAST TOLERANCE 1%
J 0
(-7125 2150);
DISPLAY 0.617021 (-7125 2150);
PAINT SKYBLUE (-7125 2150);
FORCEPROP 1 LAST LOCATION R8E19
J 0
(-7225 2250);
DISPLAY 0.617021 (-7225 2250);
PAINT AQUA (-7225 2250);
FORCEPROP 1 LAST PART_NUMBER G21796-072
J 0
(-7400 2100);
DISPLAY 0.617021 (-7400 2100);
PAINT BLUE (-7400 2100);
FORCEPROP 1 LASTPIN (-7275 2200) $PN 1
J 0
(-7263 2212);
DISPLAY 0.617021 (-7263 2212);
PAINT ORANGE (-7263 2212);
FORCEPROP 1 LAST VALUE 4.75K
J 2
(-7200 2150);
DISPLAY 0.617021 (-7200 2150);
PAINT SKYBLUE (-7200 2150);
FORCEPROP 2 LAST BOM_COST SM_CONTROLLER
J 0
(-7225 2350);
DISPLAY 1.021277 (-7225 2350);
PAINT ORANGE (-7225 2350);
DISPLAY INVISIBLE (-7225 2350);
FORCEPROP 2 LAST SEC_TYPE 0402
J 0
(-7225 2400);
DISPLAY 1.021277 (-7225 2400);
PAINT ORANGE (-7225 2400);
DISPLAY INVISIBLE (-7225 2400);
FORCEPROP 2 LAST SEC 1
J 0
(-7225 2400);
PAINT MONO (-7225 2400);
DISPLAY INVISIBLE (-7225 2400);
FORCEPROP 1 LAST PATH I361
J 0
(-7225 2350);
DISPLAY 0.978723 (-7225 2350);
PAINT WHITE (-7225 2350);
DISPLAY INVISIBLE (-7225 2350);
FORCEPROP 2 LAST ROOM BMC_MISC
J 0
(-7225 2300);
DISPLAY 1.021277 (-7225 2300);
PAINT ORANGE (-7225 2300);
DISPLAY INVISIBLE (-7225 2300);
FORCEPROP 2 LAST CDS_LOCATION R8E19
J 0
(-7225 2250);
DISPLAY 0.617021 (-7225 2250);
PAINT AQUA (-7225 2250);
DISPLAY INVISIBLE (-7225 2250);
FORCEPROP 2 LAST CDS_LIB mstr_discrete
J 0
(-7175 2200);
PAINT ORANGE (-7175 2200);
DISPLAY INVISIBLE (-7175 2200);
FORCEADD P3V3_STBY..1
(-5250 4675);
FORCEPROP 3 LASTPIN (-5250 4625) SIG_NAME P3V3_STBY\g
J 0
(-5240 4635);
DISPLAY 0.659574 (-5240 4635);
PAINT MONO (-5240 4635);
DISPLAY INVISIBLE (-5240 4635);
FORCEPROP 1 LAST VOLTAGE 3.3V
J 0
(-5295 4632);
DISPLAY 0.340426 (-5295 4632);
PAINT SKYBLUE (-5295 4632);
DISPLAY INVISIBLE (-5295 4632);
FORCEPROP 2 LAST CDS_LIB mstr_symbols
J 0
(-5250 4675);
PAINT ORANGE (-5250 4675);
DISPLAY INVISIBLE (-5250 4675);
FORCEPROP 1 LAST SIZE 1B
J 0
(-5205 4697);
DISPLAY 0.340426 (-5205 4697);
PAINT GREEN (-5205 4697);
DISPLAY INVISIBLE (-5205 4697);
FORCEPROP 1 LAST BODY_TYPE PLUMBING
J 0
(-5295 4632);
DISPLAY 0.340426 (-5295 4632);
PAINT GREEN (-5295 4632);
DISPLAY INVISIBLE (-5295 4632);
FORCEPROP 1 LAST PATH I362
J 0
(-5205 4677);
DISPLAY 0.340426 (-5205 4677);
PAINT GREEN (-5205 4677);
DISPLAY INVISIBLE (-5205 4677);
FORCEPROP 1 LAST HDL_POWER P3V3_STBY
J 0
(-5550 4550);
DISPLAY 0.872340 (-5550 4550);
PAINT ORANGE (-5550 4550);
DISPLAY INVISIBLE (-5550 4550);
FORCEADD OFFPAGE..2
(-3700 4025);
FORCEPROP 2 LAST $XR2 190 
J 0
(-3271 4025);
DISPLAY 0.638298 (-3271 4025);
PAINT MONO (-3271 4025);
FORCEPROP 2 LAST $XR1 147 
J 0
(-3391 4025);
DISPLAY 0.638298 (-3391 4025);
PAINT MONO (-3391 4025);
FORCEPROP 2 LAST $XR0 119 
J 0
(-3511 4025);
DISPLAY 0.638298 (-3511 4025);
PAINT MONO (-3511 4025);
FORCEPROP 2 LAST PATH I366
J 0
(-3250 4075);
DISPLAY 1.021277 (-3250 4075);
PAINT ORANGE (-3250 4075);
DISPLAY INVISIBLE (-3250 4075);
FORCEPROP 1 LAST OFFPAGE TRUE
J 0
(-3375 3900);
DISPLAY 0.872340 (-3375 3900);
PAINT GREEN (-3375 3900);
DISPLAY INVISIBLE (-3375 3900);
FORCEPROP 1 LAST COMMENT_BODY TRUE
J 0
(-3745 3930);
DISPLAY 0.872340 (-3745 3930);
PAINT GREEN (-3745 3930);
DISPLAY INVISIBLE (-3745 3930);
FORCEPROP 2 LAST CDS_LIB mstr_standard
J 0
(-3700 4025);
PAINT MONO (-3700 4025);
DISPLAY INVISIBLE (-3700 4025);
FORCEADD RES..1
(-4925 4025);
FORCEPROP 1 LAST LOCATION R2U4
J 0
(-4975 4075);
DISPLAY 0.617021 (-4975 4075);
PAINT AQUA (-4975 4075);
FORCEPROP 1 LAST WATTAGE 1/16W
J 2
(-4500 3975);
DISPLAY 0.617021 (-4500 3975);
PAINT SKYBLUE (-4500 3975);
FORCEPROP 1 LAST MATERIAL CHIP
J 0
(-4675 3925);
DISPLAY 0.617021 (-4675 3925);
PAINT SKYBLUE (-4675 3925);
FORCEPROP 1 LAST PACK_TYPE 0402
J 0
(-4750 3975);
DISPLAY 0.617021 (-4750 3975);
PAINT SKYBLUE (-4750 3975);
FORCEPROP 1 LASTPIN (-4825 4025) $PN 2
J 0
(-4863 4037);
DISPLAY 0.617021 (-4863 4037);
PAINT ORANGE (-4863 4037);
FORCEPROP 1 LAST TOLERANCE 1%
J 0
(-4875 3975);
DISPLAY 0.617021 (-4875 3975);
PAINT SKYBLUE (-4875 3975);
FORCEPROP 1 LASTPIN (-5025 4025) $PN 1
J 0
(-5013 4037);
DISPLAY 0.617021 (-5013 4037);
PAINT ORANGE (-5013 4037);
FORCEPROP 1 LAST VALUE 4.75K
J 2
(-4950 3975);
DISPLAY 0.617021 (-4950 3975);
PAINT SKYBLUE (-4950 3975);
FORCEPROP 1 LAST PART_NUMBER G21796-072
J 0
(-5150 3925);
DISPLAY 0.617021 (-5150 3925);
PAINT BLUE (-5150 3925);
FORCEPROP 2 LAST SEC_TYPE 0402
J 0
(-4975 4225);
DISPLAY 1.021277 (-4975 4225);
PAINT ORANGE (-4975 4225);
DISPLAY INVISIBLE (-4975 4225);
FORCEPROP 2 LAST BOM_COST SM_CONTROLLER
J 0
(-4975 4175);
DISPLAY 1.021277 (-4975 4175);
PAINT ORANGE (-4975 4175);
DISPLAY INVISIBLE (-4975 4175);
FORCEPROP 2 LAST SEC 1
J 0
(-4975 4225);
PAINT MONO (-4975 4225);
DISPLAY INVISIBLE (-4975 4225);
FORCEPROP 1 LAST PATH I367
J 0
(-4975 4175);
DISPLAY 0.978723 (-4975 4175);
PAINT WHITE (-4975 4175);
DISPLAY INVISIBLE (-4975 4175);
FORCEPROP 2 LAST ROOM BMC_MISC
J 0
(-4975 4125);
DISPLAY 1.021277 (-4975 4125);
PAINT ORANGE (-4975 4125);
DISPLAY INVISIBLE (-4975 4125);
FORCEPROP 2 LAST CDS_LOCATION R2U4
J 0
(-4975 4075);
DISPLAY 0.617021 (-4975 4075);
PAINT AQUA (-4975 4075);
DISPLAY INVISIBLE (-4975 4075);
FORCEPROP 2 LAST CDS_LIB mstr_discrete
J 0
(-4925 4025);
PAINT ORANGE (-4925 4025);
DISPLAY INVISIBLE (-4925 4025);
FORCEADD RES..1
(-6975 775);
FORCEPROP 1 LAST PACK_TYPE 0402
J 0
(-6850 625);
DISPLAY 0.617021 (-6850 625);
PAINT SKYBLUE (-6850 625);
FORCEPROP 1 LAST LOCATION R4R1
J 0
(-7025 825);
DISPLAY 0.617021 (-7025 825);
PAINT AQUA (-7025 825);
FORCEPROP 1 LAST PART_NUMBER G21796-026
J 0
(-7100 575);
DISPLAY 0.617021 (-7100 575);
PAINT BLUE (-7100 575);
FORCEPROP 1 LAST MATERIAL CHIP
J 0
(-6975 625);
DISPLAY 0.617021 (-6975 625);
PAINT SKYBLUE (-6975 625);
FORCEPROP 1 LASTPIN (-6875 775) $PN 2
J 0
(-6913 787);
DISPLAY 0.617021 (-6913 787);
PAINT ORANGE (-6913 787);
FORCEPROP 1 LASTPIN (-7075 775) $PN 1
J 0
(-7063 787);
DISPLAY 0.617021 (-7063 787);
PAINT ORANGE (-7063 787);
FORCEPROP 1 LAST VALUE 1.00K
J 2
(-7000 675);
DISPLAY 0.617021 (-7000 675);
PAINT SKYBLUE (-7000 675);
FORCEPROP 1 LAST TOLERANCE 1%
J 0
(-6975 675);
DISPLAY 0.617021 (-6975 675);
PAINT SKYBLUE (-6975 675);
FORCEPROP 1 LAST WATTAGE 1/16W
J 2
(-7000 625);
DISPLAY 0.617021 (-7000 625);
PAINT SKYBLUE (-7000 625);
FORCEPROP 0 LAST BOM_COST MIO_CHASSIS
J 0
(-7025 1075);
DISPLAY 1.021277 (-7025 1075);
PAINT ORANGE (-7025 1075);
DISPLAY INVISIBLE (-7025 1075);
FORCEPROP 0 LAST ROOM MIO_CHASSIS
J 0
(-7025 975);
DISPLAY 1.021277 (-7025 975);
PAINT ORANGE (-7025 975);
DISPLAY INVISIBLE (-7025 975);
FORCEPROP 1 LAST PATH I368
J 0
(-7025 925);
DISPLAY 0.978723 (-7025 925);
PAINT WHITE (-7025 925);
DISPLAY INVISIBLE (-7025 925);
FORCEPROP 2 LAST CDS_LOCATION R4R1
J 0
(-7025 825);
DISPLAY 0.617021 (-7025 825);
PAINT AQUA (-7025 825);
DISPLAY INVISIBLE (-7025 825);
FORCEPROP 2 LAST SEC 1
J 0
(-7025 975);
DISPLAY 0.680851 (-7025 975);
PAINT MONO (-7025 975);
DISPLAY INVISIBLE (-7025 975);
FORCEPROP 2 LAST SEC_TYPE 0402
J 0
(-7025 975);
DISPLAY 1.021277 (-7025 975);
PAINT ORANGE (-7025 975);
DISPLAY INVISIBLE (-7025 975);
FORCEPROP 2 LAST CDS_LIB mstr_discrete
J 0
(-6975 775);
PAINT ORANGE (-6975 775);
DISPLAY INVISIBLE (-6975 775);
FORCEADD P3V3_STBY..1
(-1825 3225);
FORCEPROP 3 LASTPIN (-1825 3175) SIG_NAME P3V3_STBY\g
J 0
(-1815 3185);
DISPLAY 0.659574 (-1815 3185);
PAINT MONO (-1815 3185);
DISPLAY INVISIBLE (-1815 3185);
FORCEPROP 1 LAST PATH I369
J 0
(-1780 3227);
DISPLAY 0.340426 (-1780 3227);
PAINT GREEN (-1780 3227);
DISPLAY INVISIBLE (-1780 3227);
FORCEPROP 1 LAST SIZE 1B
J 0
(-1780 3247);
DISPLAY 0.340426 (-1780 3247);
PAINT GREEN (-1780 3247);
DISPLAY INVISIBLE (-1780 3247);
FORCEPROP 1 LAST BODY_TYPE PLUMBING
J 0
(-1870 3182);
DISPLAY 0.340426 (-1870 3182);
PAINT GREEN (-1870 3182);
DISPLAY INVISIBLE (-1870 3182);
FORCEPROP 2 LAST CDS_LIB mstr_symbols
J 0
(-1825 3225);
PAINT ORANGE (-1825 3225);
DISPLAY INVISIBLE (-1825 3225);
FORCEPROP 1 LAST VOLTAGE 3.3V
J 0
(-1870 3182);
DISPLAY 0.340426 (-1870 3182);
PAINT SKYBLUE (-1870 3182);
DISPLAY INVISIBLE (-1870 3182);
FORCEPROP 1 LAST HDL_POWER P3V3_STBY
J 0
(-2125 3100);
DISPLAY 0.872340 (-2125 3100);
PAINT ORANGE (-2125 3100);
DISPLAY INVISIBLE (-2125 3100);
FORCEADD CAP_A..1
(-1825 2925);
FORCEPROP 1 LAST PART_NUMBER A36096-030
J 0
(-1775 2775);
DISPLAY 0.617021 (-1775 2775);
PAINT BLUE (-1775 2775);
FORCEPROP 1 LAST LOCATION C2T3
J 0
(-1775 3025);
DISPLAY 0.617021 (-1775 3025);
PAINT AQUA (-1775 3025);
FORCEPROP 1 LAST VALUE 0.1UF
J 0
(-1775 2975);
DISPLAY 0.617021 (-1775 2975);
PAINT SKYBLUE (-1775 2975);
FORCEPROP 1 LAST TOLERANCE 10%
J 0
(-1775 2875);
DISPLAY 0.617021 (-1775 2875);
PAINT SKYBLUE (-1775 2875);
FORCEPROP 1 LAST PACK_TYPE 0402V
J 0
(-1775 2725);
DISPLAY 0.617021 (-1775 2725);
PAINT SKYBLUE (-1775 2725);
FORCEPROP 1 LAST VOLTAGE 16V
J 0
(-1775 2925);
DISPLAY 0.617021 (-1775 2925);
PAINT SKYBLUE (-1775 2925);
FORCEPROP 1 LAST MATERIAL X7R
J 0
(-1775 2825);
DISPLAY 0.617021 (-1775 2825);
PAINT SKYBLUE (-1775 2825);
FORCEPROP 1 LASTPIN (-1825 3025) $PN 1
J 0
(-1815 3005);
DISPLAY 0.617021 (-1815 3005);
PAINT ORANGE (-1815 3005);
FORCEPROP 1 LASTPIN (-1825 2825) $PN 2
J 0
(-1815 2805);
DISPLAY 0.617021 (-1815 2805);
PAINT ORANGE (-1815 2805);
FORCEPROP 2 LAST SEC 1
J 0
(-1775 3075);
DISPLAY 0.680851 (-1775 3075);
PAINT MONO (-1775 3075);
DISPLAY INVISIBLE (-1775 3075);
FORCEPROP 2 LAST SEC_TYPE 0402V
J 0
(-1775 3125);
DISPLAY 1.021277 (-1775 3125);
PAINT ORANGE (-1775 3125);
DISPLAY INVISIBLE (-1775 3125);
FORCEPROP 2 LAST CDS_SEC 1
J 0
(-1775 3075);
PAINT ORANGE (-1775 3075);
DISPLAY INVISIBLE (-1775 3075);
FORCEPROP 2 LAST BOM_COST MIO_CHASSIS
J 0
(-1775 3125);
DISPLAY 1.021277 (-1775 3125);
PAINT ORANGE (-1775 3125);
DISPLAY INVISIBLE (-1775 3125);
FORCEPROP 2 LAST ROOM MIO_CHASSIS
J 0
(-1775 3075);
DISPLAY 1.021277 (-1775 3075);
PAINT ORANGE (-1775 3075);
DISPLAY INVISIBLE (-1775 3075);
FORCEPROP 1 LAST PATH I370
J 0
(-1775 3075);
DISPLAY 0.978723 (-1775 3075);
PAINT WHITE (-1775 3075);
DISPLAY INVISIBLE (-1775 3075);
FORCEPROP 2 LAST CDS_LOCATION C2T3
J 0
(-1775 3025);
DISPLAY 0.617021 (-1775 3025);
PAINT AQUA (-1775 3025);
DISPLAY INVISIBLE (-1775 3025);
FORCEPROP 2 LAST CDS_LIB dev_discrete
J 0
(-1825 2925);
PAINT ORANGE (-1825 2925);
DISPLAY INVISIBLE (-1825 2925);
FORCEADD GND..1
(-1825 2625);
FORCEPROP 3 LASTPIN (-1825 2675) SIG_NAME GND\g
J 0
(-1815 2685);
DISPLAY 0.659574 (-1815 2685);
PAINT MONO (-1815 2685);
DISPLAY INVISIBLE (-1815 2685);
FORCEPROP 1 LAST PATH I371
J 0
(-1750 2625);
DISPLAY 0.872340 (-1750 2625);
PAINT AQUA (-1750 2625);
DISPLAY INVISIBLE (-1750 2625);
FORCEPROP 1 LAST SIZE 1B
J 0
(-1750 2575);
DISPLAY 0.872340 (-1750 2575);
PAINT AQUA (-1750 2575);
DISPLAY INVISIBLE (-1750 2575);
FORCEPROP 1 LAST BODY_TYPE PLUMBING
J 0
(-1870 2582);
DISPLAY 0.340426 (-1870 2582);
PAINT GREEN (-1870 2582);
DISPLAY INVISIBLE (-1870 2582);
FORCEPROP 1 LAST HDL_POWER GND
J 0
(-1825 2775);
DISPLAY 0.872340 (-1825 2775);
PAINT GREEN (-1825 2775);
DISPLAY INVISIBLE (-1825 2775);
FORCEPROP 1 LAST VOLTAGE 0.0V
J 0
(-1870 2582);
DISPLAY 0.340426 (-1870 2582);
PAINT SKYBLUE (-1870 2582);
DISPLAY INVISIBLE (-1870 2582);
FORCEPROP 2 LAST CDS_LIB mstr_symbols
J 0
(-1825 2625);
PAINT ORANGE (-1825 2625);
DISPLAY INVISIBLE (-1825 2625);
FORCEADD OFFPAGE..1
(-3500 1150);
FORCEPROP 2 LAST $XR4 191 
J 0
(-4232 1150);
DISPLAY 0.638298 (-4232 1150);
PAINT MONO (-4232 1150);
FORCEPROP 2 LAST $XR3 183 
J 0
(-4112 1150);
DISPLAY 0.638298 (-4112 1150);
PAINT MONO (-4112 1150);
FORCEPROP 2 LAST $XR2 118 
J 0
(-3992 1150);
DISPLAY 0.638298 (-3992 1150);
PAINT MONO (-3992 1150);
FORCEPROP 2 LAST $XR1 200 
J 0
(-3872 1150);
DISPLAY 0.638298 (-3872 1150);
PAINT MONO (-3872 1150);
FORCEPROP 2 LAST $XR0 196 
J 0
(-3752 1150);
DISPLAY 0.638298 (-3752 1150);
PAINT MONO (-3752 1150);
FORCEPROP 2 LAST PATH I373
J 0
(-3450 1225);
DISPLAY 1.021277 (-3450 1225);
PAINT ORANGE (-3450 1225);
DISPLAY INVISIBLE (-3450 1225);
FORCEPROP 1 LAST COMMENT_BODY TRUE
J 0
(-3375 1050);
DISPLAY 0.872340 (-3375 1050);
PAINT GREEN (-3375 1050);
DISPLAY INVISIBLE (-3375 1050);
FORCEPROP 1 LAST OFFPAGE TRUE
J 0
(-3175 1025);
DISPLAY 0.872340 (-3175 1025);
PAINT GREEN (-3175 1025);
DISPLAY INVISIBLE (-3175 1025);
FORCEPROP 2 LAST CDS_LIB mstr_standard
J 0
(-3500 1150);
PAINT ORANGE (-3500 1150);
DISPLAY INVISIBLE (-3500 1150);
FORCEADD TTL1G07_A..1
(-2800 1150);
FORCEPROP 2 LASTPIN (-2650 1150) SIG_NAME RST_BMC_SRST_R2_N
J 0
(-2560 1160);
DISPLAY 0.617021 (-2560 1160);
PAINT ORANGE (-2560 1160);
FORCEPROP 2 LASTPROP $XRERR UNIQUE?
J 0
(-2800 1160);
DISPLAY 0.638298 (-2800 1160);
PAINT MONO (-2800 1160);
DISPLAY INVISIBLE (-2800 1160);
FORCEPROP 2 LASTPIN (-2650 1150) $PN 4
J 0
(-2640 1160);
DISPLAY 0.617021 (-2640 1160);
PAINT ORANGE (-2640 1160);
FORCEPROP 1 LAST LOCATION U8D2
J 0
(-2850 1350);
DISPLAY 0.617021 (-2850 1350);
PAINT AQUA (-2850 1350);
FORCEPROP 1 LAST VALUE 74LVC1G07
J 1
(-2800 1250);
DISPLAY 0.617021 (-2800 1250);
PAINT SKYBLUE (-2800 1250);
FORCEPROP 1 LAST MATERIAL IC
J 0
(-2850 1300);
DISPLAY 0.617021 (-2850 1300);
PAINT SKYBLUE (-2850 1300);
FORCEPROP 2 LASTPIN (-2900 1150) $PN 2
J 2
(-2910 1160);
DISPLAY 0.617021 (-2910 1160);
PAINT ORANGE (-2910 1160);
FORCEPROP 1 LAST PART_NUMBER C88419-001
J 0
(-2850 1015);
DISPLAY 0.617021 (-2850 1015);
PAINT BLUE (-2850 1015);
FORCEPROP 1 LAST POWER_GROUP VCC=P3V3_STBY;GND=GND
J 1
(-2850 960);
DISPLAY 0.617021 (-2850 960);
PAINT ORANGE (-2850 960);
FORCEPROP 2 LAST CDS_LIB mstr_ttl
J 0
(-2800 1150);
PAINT ORANGE (-2800 1150);
DISPLAY INVISIBLE (-2800 1150);
FORCEPROP 1 LAST PATH I374
J 0
(-2750 1200);
DISPLAY 0.978723 (-2750 1200);
PAINT WHITE (-2750 1200);
DISPLAY INVISIBLE (-2750 1200);
FORCEPROP 1 LAST PACK_TYPE SOP
J 0
(-2850 1400);
DISPLAY 0.978723 (-2850 1400);
PAINT SKYBLUE (-2850 1400);
DISPLAY INVISIBLE (-2850 1400);
FORCEPROP 2 LAST SEC_TYPE SOP
J 0
(-2850 1400);
DISPLAY 1.021277 (-2850 1400);
PAINT ORANGE (-2850 1400);
DISPLAY INVISIBLE (-2850 1400);
FORCEPROP 2 LAST SEC 1
J 0
(-2850 1400);
DISPLAY 0.680851 (-2850 1400);
PAINT MONO (-2850 1400);
DISPLAY INVISIBLE (-2850 1400);
FORCEPROP 2 LAST CDS_LOCATION U8D2
J 0
(-2850 1350);
DISPLAY 0.617021 (-2850 1350);
PAINT AQUA (-2850 1350);
DISPLAY INVISIBLE (-2850 1350);
FORCEADD OFFPAGE..2
(-800 1150);
FORCEPROP 2 LAST $XR3 ?
J 0
(-421 1150);
DISPLAY 0.638298 (-421 1150);
PAINT MONO (-421 1150);
FORCEPROP 2 LAST $XR2 ?
J 0
(-296 1150);
DISPLAY 0.638298 (-296 1150);
PAINT MONO (-296 1150);
FORCEPROP 2 LAST $XR1 249 
J 0
(-491 1150);
DISPLAY 0.638298 (-491 1150);
PAINT MONO (-491 1150);
FORCEPROP 2 LAST $XR0 184 
J 0
(-611 1150);
DISPLAY 0.638298 (-611 1150);
PAINT MONO (-611 1150);
FORCEPROP 1 LAST OFFPAGE TRUE
J 0
(-475 1025);
DISPLAY 0.872340 (-475 1025);
PAINT GREEN (-475 1025);
DISPLAY INVISIBLE (-475 1025);
FORCEPROP 2 LAST PATH I375
J 0
(-750 1225);
DISPLAY 1.021277 (-750 1225);
PAINT ORANGE (-750 1225);
DISPLAY INVISIBLE (-750 1225);
FORCEPROP 1 LAST COMMENT_BODY TRUE
J 0
(-845 1055);
DISPLAY 0.872340 (-845 1055);
PAINT GREEN (-845 1055);
DISPLAY INVISIBLE (-845 1055);
FORCEPROP 2 LAST CDS_LIB mstr_standard
J 0
(-800 1150);
PAINT ORANGE (-800 1150);
DISPLAY INVISIBLE (-800 1150);
FORCEADD CAP_A..1
(-500 1725);
FORCEPROP 1 LAST PART_NUMBER A36096-030
J 0
(-450 1575);
DISPLAY 0.617021 (-450 1575);
PAINT BLUE (-450 1575);
FORCEPROP 1 LAST LOCATION C8D1
J 0
(-450 1825);
DISPLAY 0.617021 (-450 1825);
PAINT AQUA (-450 1825);
FORCEPROP 1 LASTPIN (-500 1825) $PN 1
J 0
(-490 1805);
DISPLAY 0.617021 (-490 1805);
PAINT ORANGE (-490 1805);
FORCEPROP 1 LAST VALUE 0.1UF
J 0
(-450 1775);
DISPLAY 0.617021 (-450 1775);
PAINT SKYBLUE (-450 1775);
FORCEPROP 1 LAST TOLERANCE 10%
J 0
(-450 1675);
DISPLAY 0.617021 (-450 1675);
PAINT SKYBLUE (-450 1675);
FORCEPROP 1 LAST VOLTAGE 16V
J 0
(-450 1725);
DISPLAY 0.617021 (-450 1725);
PAINT SKYBLUE (-450 1725);
FORCEPROP 1 LAST MATERIAL X7R
J 0
(-450 1625);
DISPLAY 0.617021 (-450 1625);
PAINT SKYBLUE (-450 1625);
FORCEPROP 1 LASTPIN (-500 1625) $PN 2
J 0
(-490 1605);
DISPLAY 0.617021 (-490 1605);
PAINT ORANGE (-490 1605);
FORCEPROP 1 LAST PACK_TYPE 0402V
J 0
(-450 1525);
DISPLAY 0.617021 (-450 1525);
PAINT SKYBLUE (-450 1525);
FORCEPROP 2 LAST SEC_TYPE 0402V
J 0
(-450 1925);
DISPLAY 1.021277 (-450 1925);
PAINT ORANGE (-450 1925);
DISPLAY INVISIBLE (-450 1925);
FORCEPROP 2 LAST SEC 1
J 0
(-450 1925);
DISPLAY 0.680851 (-450 1925);
PAINT MONO (-450 1925);
DISPLAY INVISIBLE (-450 1925);
FORCEPROP 1 LAST PATH I376
J 0
(-450 1875);
DISPLAY 0.978723 (-450 1875);
PAINT WHITE (-450 1875);
DISPLAY INVISIBLE (-450 1875);
FORCEPROP 2 LAST CDS_LOCATION C8D1
J 0
(-450 1825);
DISPLAY 0.617021 (-450 1825);
PAINT AQUA (-450 1825);
DISPLAY INVISIBLE (-450 1825);
FORCEPROP 2 LAST CDS_SEC 1
J 0
(-450 1875);
PAINT ORANGE (-450 1875);
DISPLAY INVISIBLE (-450 1875);
FORCEPROP 2 LAST CDS_LIB dev_discrete
J 0
(-500 1725);
PAINT ORANGE (-500 1725);
DISPLAY INVISIBLE (-500 1725);
FORCEADD GND..1
(-500 1475);
FORCEPROP 3 LASTPIN (-500 1525) SIG_NAME GND\g
J 0
(-490 1535);
DISPLAY 0.659574 (-490 1535);
PAINT MONO (-490 1535);
DISPLAY INVISIBLE (-490 1535);
FORCEPROP 1 LAST HDL_POWER GND
J 0
(-500 1625);
DISPLAY 0.872340 (-500 1625);
PAINT GREEN (-500 1625);
DISPLAY INVISIBLE (-500 1625);
FORCEPROP 2 LAST CDS_LIB mstr_symbols
J 0
(-500 1475);
PAINT ORANGE (-500 1475);
DISPLAY INVISIBLE (-500 1475);
FORCEPROP 1 LAST SIZE 1B
J 0
(-425 1425);
DISPLAY 0.872340 (-425 1425);
PAINT AQUA (-425 1425);
DISPLAY INVISIBLE (-425 1425);
FORCEPROP 1 LAST PATH I377
J 0
(-425 1475);
DISPLAY 0.872340 (-425 1475);
PAINT AQUA (-425 1475);
DISPLAY INVISIBLE (-425 1475);
FORCEPROP 1 LAST VOLTAGE 0.0V
J 0
(-545 1432);
DISPLAY 0.340426 (-545 1432);
PAINT SKYBLUE (-545 1432);
DISPLAY INVISIBLE (-545 1432);
FORCEPROP 1 LAST BODY_TYPE PLUMBING
J 0
(-545 1432);
DISPLAY 0.340426 (-545 1432);
PAINT GREEN (-545 1432);
DISPLAY INVISIBLE (-545 1432);
FORCEADD P3V3_STBY..1
(-500 1950);
FORCEPROP 3 LASTPIN (-500 1900) SIG_NAME P3V3_STBY\g
J 0
(-490 1910);
DISPLAY 0.659574 (-490 1910);
PAINT MONO (-490 1910);
DISPLAY INVISIBLE (-490 1910);
FORCEPROP 2 LAST CDS_LIB mstr_symbols
J 0
(-500 1950);
PAINT ORANGE (-500 1950);
DISPLAY INVISIBLE (-500 1950);
FORCEPROP 1 LAST SIZE 1B
J 0
(-455 1972);
DISPLAY 0.340426 (-455 1972);
PAINT GREEN (-455 1972);
DISPLAY INVISIBLE (-455 1972);
FORCEPROP 1 LAST PATH I378
J 0
(-455 1952);
DISPLAY 0.340426 (-455 1952);
PAINT GREEN (-455 1952);
DISPLAY INVISIBLE (-455 1952);
FORCEPROP 1 LAST VOLTAGE 3.3V
J 0
(-545 1907);
DISPLAY 0.340426 (-545 1907);
PAINT SKYBLUE (-545 1907);
DISPLAY INVISIBLE (-545 1907);
FORCEPROP 1 LAST BODY_TYPE PLUMBING
J 0
(-545 1907);
DISPLAY 0.340426 (-545 1907);
PAINT GREEN (-545 1907);
DISPLAY INVISIBLE (-545 1907);
FORCEPROP 1 LAST HDL_POWER P3V3_STBY
J 0
(-800 1825);
DISPLAY 0.872340 (-800 1825);
PAINT ORANGE (-800 1825);
DISPLAY INVISIBLE (-800 1825);
FORCEADD RES..1
(-1450 875);
FORCEPROP 1 LAST VALUE 0.0
J 2
(-1475 775);
DISPLAY 0.617021 (-1475 775);
PAINT SKYBLUE (-1475 775);
FORCEPROP 1 LAST TOLERANCE 5%
J 0
(-1450 775);
DISPLAY 0.617021 (-1450 775);
PAINT SKYBLUE (-1450 775);
FORCEPROP 1 LAST PACK_TYPE 0402
J 0
(-1200 725);
DISPLAY 0.617021 (-1200 725);
PAINT SKYBLUE (-1200 725);
FORCEPROP 1 LAST MATERIAL CHIP
J 0
(-1450 725);
DISPLAY 0.617021 (-1450 725);
PAINT SKYBLUE (-1450 725);
FORCEPROP 1 LAST WATTAGE 1/16W
J 2
(-1475 725);
DISPLAY 0.617021 (-1475 725);
PAINT SKYBLUE (-1475 725);
FORCEPROP 1 LASTPIN (-1350 875) $PN 2
J 0
(-1388 887);
DISPLAY 0.617021 (-1388 887);
PAINT ORANGE (-1388 887);
FORCEPROP 1 LAST PART_NUMBER G21497-005
J 0
(-1500 975);
DISPLAY 0.617021 (-1500 975);
PAINT BLUE (-1500 975);
FORCEPROP 1 LAST LOCATION R9E14
J 0
(-1500 925);
DISPLAY 0.617021 (-1500 925);
PAINT AQUA (-1500 925);
FORCEPROP 1 LASTPIN (-1550 875) $PN 1
J 0
(-1538 887);
DISPLAY 0.617021 (-1538 887);
PAINT ORANGE (-1538 887);
FORCEPROP 2 LAST SEC_TYPE 0402
J 0
(-1500 1075);
DISPLAY 1.021277 (-1500 1075);
PAINT ORANGE (-1500 1075);
DISPLAY INVISIBLE (-1500 1075);
FORCEPROP 2 LAST SEC 1
J 0
(-1500 1075);
PAINT MONO (-1500 1075);
DISPLAY INVISIBLE (-1500 1075);
FORCEPROP 1 LAST PATH I379
J 0
(-1500 1025);
DISPLAY 0.978723 (-1500 1025);
PAINT WHITE (-1500 1025);
DISPLAY INVISIBLE (-1500 1025);
FORCEPROP 2 LAST CDS_LOCATION R9E14
J 0
(-1500 925);
DISPLAY 0.617021 (-1500 925);
PAINT AQUA (-1500 925);
DISPLAY INVISIBLE (-1500 925);
FORCEPROP 2 LAST CDS_LIB mstr_discrete
J 0
(-1450 875);
PAINT ORANGE (-1450 875);
DISPLAY INVISIBLE (-1450 875);
FORCEADD OFFPAGE..2
(-800 875);
FORCEPROP 2 LAST $XR0 143 
J 0
(-611 875);
DISPLAY 0.638298 (-611 875);
PAINT MONO (-611 875);
FORCEPROP 2 LAST $XR1 119 
J 0
(-491 875);
DISPLAY 0.638298 (-491 875);
PAINT MONO (-491 875);
FORCEPROP 1 LAST OFFPAGE TRUE
J 0
(-475 750);
DISPLAY 0.872340 (-475 750);
PAINT GREEN (-475 750);
DISPLAY INVISIBLE (-475 750);
FORCEPROP 2 LAST PATH I380
J 0
(-750 950);
DISPLAY 1.021277 (-750 950);
PAINT ORANGE (-750 950);
DISPLAY INVISIBLE (-750 950);
FORCEPROP 1 LAST COMMENT_BODY TRUE
J 0
(-845 780);
DISPLAY 0.872340 (-845 780);
PAINT GREEN (-845 780);
DISPLAY INVISIBLE (-845 780);
FORCEPROP 2 LAST CDS_LIB mstr_standard
J 0
(-800 875);
PAINT ORANGE (-800 875);
DISPLAY INVISIBLE (-800 875);
FORCEADD OFFPAGE..2
(-5950 3425);
FORCEPROP 2 LAST $XR2 190 
J 0
(-5521 3425);
DISPLAY 0.638298 (-5521 3425);
PAINT MONO (-5521 3425);
FORCEPROP 2 LAST $XR1 145 
J 0
(-5641 3425);
DISPLAY 0.638298 (-5641 3425);
PAINT MONO (-5641 3425);
FORCEPROP 2 LAST $XR0 118 
J 0
(-5761 3425);
DISPLAY 0.638298 (-5761 3425);
PAINT MONO (-5761 3425);
FORCEPROP 2 LAST PATH I381
J 0
(-5500 3475);
DISPLAY 1.021277 (-5500 3475);
PAINT ORANGE (-5500 3475);
DISPLAY INVISIBLE (-5500 3475);
FORCEPROP 1 LAST OFFPAGE TRUE
J 0
(-5625 3300);
DISPLAY 0.872340 (-5625 3300);
PAINT GREEN (-5625 3300);
DISPLAY INVISIBLE (-5625 3300);
FORCEPROP 2 LAST CDS_LIB mstr_standard
J 0
(-5950 3425);
PAINT ORANGE (-5950 3425);
DISPLAY INVISIBLE (-5950 3425);
FORCEPROP 1 LAST COMMENT_BODY TRUE
J 0
(-5995 3330);
DISPLAY 0.872340 (-5995 3330);
PAINT GREEN (-5995 3330);
DISPLAY INVISIBLE (-5995 3330);
FORCEADD RES..1
(-7175 3425);
FORCEPROP 1 LAST TOLERANCE 1%
J 0
(-7125 3375);
DISPLAY 0.617021 (-7125 3375);
PAINT SKYBLUE (-7125 3375);
FORCEPROP 1 LAST PACK_TYPE 0402
J 0
(-7000 3375);
DISPLAY 0.617021 (-7000 3375);
PAINT SKYBLUE (-7000 3375);
FORCEPROP 1 LAST MATERIAL CHIP
J 0
(-6925 3325);
DISPLAY 0.617021 (-6925 3325);
PAINT SKYBLUE (-6925 3325);
FORCEPROP 1 LAST WATTAGE 1/16W
J 2
(-6750 3375);
DISPLAY 0.617021 (-6750 3375);
PAINT SKYBLUE (-6750 3375);
FORCEPROP 1 LASTPIN (-7075 3425) $PN 2
J 0
(-7113 3437);
DISPLAY 0.617021 (-7113 3437);
PAINT ORANGE (-7113 3437);
FORCEPROP 1 LAST LOCATION R1L7
J 0
(-7225 3475);
DISPLAY 0.617021 (-7225 3475);
PAINT AQUA (-7225 3475);
FORCEPROP 1 LAST PART_NUMBER G21796-072
J 0
(-7400 3325);
DISPLAY 0.617021 (-7400 3325);
PAINT BLUE (-7400 3325);
FORCEPROP 1 LASTPIN (-7275 3425) $PN 1
J 0
(-7263 3437);
DISPLAY 0.617021 (-7263 3437);
PAINT ORANGE (-7263 3437);
FORCEPROP 1 LAST VALUE 4.75K
J 2
(-7200 3375);
DISPLAY 0.617021 (-7200 3375);
PAINT SKYBLUE (-7200 3375);
FORCEPROP 2 LAST SEC_TYPE 0402
J 0
(-7225 3625);
DISPLAY 1.021277 (-7225 3625);
PAINT ORANGE (-7225 3625);
DISPLAY INVISIBLE (-7225 3625);
FORCEPROP 2 LAST SEC 1
J 0
(-7225 3625);
PAINT MONO (-7225 3625);
DISPLAY INVISIBLE (-7225 3625);
FORCEPROP 2 LAST BOM_COST SM_CONTROLLER
J 0
(-7225 3575);
DISPLAY 1.021277 (-7225 3575);
PAINT ORANGE (-7225 3575);
DISPLAY INVISIBLE (-7225 3575);
FORCEPROP 1 LAST PATH I382
J 0
(-7225 3575);
DISPLAY 0.978723 (-7225 3575);
PAINT WHITE (-7225 3575);
DISPLAY INVISIBLE (-7225 3575);
FORCEPROP 2 LAST ROOM BMC_MISC
J 0
(-7225 3525);
DISPLAY 1.021277 (-7225 3525);
PAINT ORANGE (-7225 3525);
DISPLAY INVISIBLE (-7225 3525);
FORCEPROP 2 LAST CDS_LIB mstr_discrete
J 0
(-7175 3425);
PAINT ORANGE (-7175 3425);
DISPLAY INVISIBLE (-7175 3425);
FORCEPROP 2 LAST CDS_LOCATION R1L7
J 0
(-7225 3475);
DISPLAY 0.617021 (-7225 3475);
PAINT AQUA (-7225 3475);
DISPLAY INVISIBLE (-7225 3475);
FORCEADD P3V3_STBY..1
(-3950 2925);
FORCEPROP 3 LASTPIN (-3950 2875) SIG_NAME P3V3_STBY\g
J 0
(-3940 2885);
DISPLAY 0.659574 (-3940 2885);
PAINT MONO (-3940 2885);
DISPLAY INVISIBLE (-3940 2885);
FORCEPROP 1 LAST VOLTAGE 3.3V
J 0
(-3995 2882);
DISPLAY 0.340426 (-3995 2882);
PAINT SKYBLUE (-3995 2882);
DISPLAY INVISIBLE (-3995 2882);
FORCEPROP 2 LAST CDS_LIB mstr_symbols
J 0
(-3950 2925);
PAINT ORANGE (-3950 2925);
DISPLAY INVISIBLE (-3950 2925);
FORCEPROP 1 LAST SIZE 1B
J 0
(-3905 2947);
DISPLAY 0.340426 (-3905 2947);
PAINT GREEN (-3905 2947);
DISPLAY INVISIBLE (-3905 2947);
FORCEPROP 1 LAST BODY_TYPE PLUMBING
J 0
(-3995 2882);
DISPLAY 0.340426 (-3995 2882);
PAINT GREEN (-3995 2882);
DISPLAY INVISIBLE (-3995 2882);
FORCEPROP 1 LAST PATH I384
J 0
(-3905 2927);
DISPLAY 0.340426 (-3905 2927);
PAINT GREEN (-3905 2927);
DISPLAY INVISIBLE (-3905 2927);
FORCEPROP 1 LAST HDL_POWER P3V3_STBY
J 0
(-4250 2800);
DISPLAY 0.872340 (-4250 2800);
PAINT ORANGE (-4250 2800);
DISPLAY INVISIBLE (-4250 2800);
FORCEADD RES..2
(-3950 2650);
FORCEPROP 1 LAST VALUE 4.75K
J 0
(-3905 2725);
DISPLAY 0.617021 (-3905 2725);
PAINT SKYBLUE (-3905 2725);
FORCEPROP 1 LAST LOCATION R8E32
J 0
(-3905 2775);
DISPLAY 0.617021 (-3905 2775);
PAINT AQUA (-3905 2775);
FORCEPROP 1 LAST MATERIAL CHIP
J 0
(-3910 2575);
DISPLAY 0.617021 (-3910 2575);
PAINT SKYBLUE (-3910 2575);
FORCEPROP 1 LAST WATTAGE 1/16W
J 0
(-3910 2625);
DISPLAY 0.617021 (-3910 2625);
PAINT SKYBLUE (-3910 2625);
FORCEPROP 1 LASTPIN (-3950 2750) $PN 1
J 0
(-3945 2712);
DISPLAY 0.617021 (-3945 2712);
PAINT ORANGE (-3945 2712);
FORCEPROP 1 LAST TOLERANCE 1%
J 0
(-3905 2675);
DISPLAY 0.617021 (-3905 2675);
PAINT SKYBLUE (-3905 2675);
FORCEPROP 1 LASTPIN (-3950 2550) $PN 2
J 0
(-3945 2560);
DISPLAY 0.617021 (-3945 2560);
PAINT ORANGE (-3945 2560);
FORCEPROP 1 LAST PACK_TYPE 0402
J 0
(-3910 2475);
DISPLAY 0.617021 (-3910 2475);
PAINT SKYBLUE (-3910 2475);
FORCEPROP 1 LAST PART_NUMBER G21796-072
J 0
(-3910 2525);
DISPLAY 0.617021 (-3910 2525);
PAINT BLUE (-3910 2525);
FORCEPROP 0 LAST BOM_COST MIO_CHASSIS
J 0
(-3900 2975);
DISPLAY 1.021277 (-3900 2975);
PAINT ORANGE (-3900 2975);
DISPLAY INVISIBLE (-3900 2975);
FORCEPROP 2 LAST SEC_TYPE 0402
J 0
(-3900 2875);
DISPLAY 1.021277 (-3900 2875);
PAINT ORANGE (-3900 2875);
DISPLAY INVISIBLE (-3900 2875);
FORCEPROP 2 LAST SEC 1
J 0
(-3900 2875);
DISPLAY 0.680851 (-3900 2875);
PAINT MONO (-3900 2875);
DISPLAY INVISIBLE (-3900 2875);
FORCEPROP 1 LAST PATH I385
J 0
(-3900 2825);
DISPLAY 0.978723 (-3900 2825);
PAINT WHITE (-3900 2825);
DISPLAY INVISIBLE (-3900 2825);
FORCEPROP 0 LAST ROOM MIO_CHASSIS
J 0
(-3900 2875);
DISPLAY 1.021277 (-3900 2875);
PAINT ORANGE (-3900 2875);
DISPLAY INVISIBLE (-3900 2875);
FORCEPROP 2 LAST CDS_LIB mstr_discrete
J 0
(-3950 2650);
PAINT ORANGE (-3950 2650);
DISPLAY INVISIBLE (-3950 2650);
FORCEPROP 2 LAST CDS_LOCATION R8E32
J 0
(-3905 2775);
DISPLAY 0.617021 (-3905 2775);
PAINT AQUA (-3905 2775);
DISPLAY INVISIBLE (-3905 2775);
FORCEADD RES..1
(-1925 1150);
FORCEPROP 1 LAST PART_NUMBER G21796-074
J 0
(-1975 1250);
DISPLAY 0.617021 (-1975 1250);
PAINT BLUE (-1975 1250);
FORCEPROP 1 LASTPIN (-1825 1150) $PN 2
J 0
(-1863 1162);
DISPLAY 0.617021 (-1863 1162);
PAINT ORANGE (-1863 1162);
FORCEPROP 1 LAST TOLERANCE 1%
J 0
(-1925 1050);
DISPLAY 0.617021 (-1925 1050);
PAINT SKYBLUE (-1925 1050);
FORCEPROP 1 LAST LOCATION R8D22
J 0
(-1975 1200);
DISPLAY 0.617021 (-1975 1200);
PAINT AQUA (-1975 1200);
FORCEPROP 1 LASTPIN (-2025 1150) $PN 1
J 0
(-2013 1162);
DISPLAY 0.617021 (-2013 1162);
PAINT ORANGE (-2013 1162);
FORCEPROP 1 LAST PACK_TYPE 0402
J 0
(-1775 1000);
DISPLAY 0.617021 (-1775 1000);
PAINT SKYBLUE (-1775 1000);
FORCEPROP 1 LAST VALUE 33.2
J 2
(-1950 1050);
DISPLAY 0.617021 (-1950 1050);
PAINT SKYBLUE (-1950 1050);
FORCEPROP 1 LAST WATTAGE 1/16W
J 2
(-1950 1000);
DISPLAY 0.617021 (-1950 1000);
PAINT SKYBLUE (-1950 1000);
FORCEPROP 1 LAST MATERIAL CHIP
J 0
(-1925 1000);
DISPLAY 0.617021 (-1925 1000);
PAINT SKYBLUE (-1925 1000);
FORCEPROP 0 LAST ROOM BMC_MISC
J 0
(-1975 1350);
DISPLAY 1.021277 (-1975 1350);
PAINT ORANGE (-1975 1350);
DISPLAY INVISIBLE (-1975 1350);
FORCEPROP 1 LAST PATH I386
J 0
(-1975 1300);
DISPLAY 0.978723 (-1975 1300);
PAINT WHITE (-1975 1300);
DISPLAY INVISIBLE (-1975 1300);
FORCEPROP 2 LAST SEC 1
J 0
(-1975 1350);
PAINT MONO (-1975 1350);
DISPLAY INVISIBLE (-1975 1350);
FORCEPROP 0 LAST BOM_COST SM
J 0
(-1975 1450);
DISPLAY 1.021277 (-1975 1450);
PAINT ORANGE (-1975 1450);
DISPLAY INVISIBLE (-1975 1450);
FORCEPROP 2 LAST SEC_TYPE 0402
J 0
(-1975 1350);
DISPLAY 1.021277 (-1975 1350);
PAINT ORANGE (-1975 1350);
DISPLAY INVISIBLE (-1975 1350);
FORCEPROP 2 LAST CDS_LOCATION R8D22
J 0
(-1975 1200);
DISPLAY 0.617021 (-1975 1200);
PAINT AQUA (-1975 1200);
DISPLAY INVISIBLE (-1975 1200);
FORCEPROP 2 LAST CDS_LIB mstr_discrete
J 0
(-1925 1150);
PAINT ORANGE (-1925 1150);
DISPLAY INVISIBLE (-1925 1150);
FORCEADD RES..1
(-1425 1375);
FORCEPROP 1 LAST PART_NUMBER G21796-074
J 0
(-1475 1475);
DISPLAY 0.617021 (-1475 1475);
PAINT BLUE (-1475 1475);
FORCEPROP 1 LASTPIN (-1325 1375) $PN 2
J 0
(-1363 1387);
DISPLAY 0.617021 (-1363 1387);
PAINT ORANGE (-1363 1387);
FORCEPROP 1 LAST LOCATION R8D36
J 0
(-1475 1425);
DISPLAY 0.617021 (-1475 1425);
PAINT AQUA (-1475 1425);
FORCEPROP 1 LASTPIN (-1525 1375) $PN 1
J 0
(-1513 1387);
DISPLAY 0.617021 (-1513 1387);
PAINT ORANGE (-1513 1387);
FORCEPROP 1 LAST TOLERANCE 1%
J 0
(-1425 1275);
DISPLAY 0.617021 (-1425 1275);
PAINT SKYBLUE (-1425 1275);
FORCEPROP 1 LAST VALUE 33.2
J 2
(-1450 1275);
DISPLAY 0.617021 (-1450 1275);
PAINT SKYBLUE (-1450 1275);
FORCEPROP 1 LAST WATTAGE 1/16W
J 2
(-1450 1225);
DISPLAY 0.617021 (-1450 1225);
PAINT SKYBLUE (-1450 1225);
FORCEPROP 1 LAST PACK_TYPE 0402
J 0
(-1275 1225);
DISPLAY 0.617021 (-1275 1225);
PAINT SKYBLUE (-1275 1225);
FORCEPROP 1 LAST MATERIAL CHIP
J 0
(-1425 1225);
DISPLAY 0.617021 (-1425 1225);
PAINT SKYBLUE (-1425 1225);
FORCEPROP 0 LAST ROOM BMC_MISC
J 0
(-1475 1575);
DISPLAY 1.021277 (-1475 1575);
PAINT ORANGE (-1475 1575);
DISPLAY INVISIBLE (-1475 1575);
FORCEPROP 2 LAST SEC 1
J 0
(-1475 1575);
PAINT MONO (-1475 1575);
DISPLAY INVISIBLE (-1475 1575);
FORCEPROP 0 LAST BOM_COST SM
J 0
(-1475 1675);
DISPLAY 1.021277 (-1475 1675);
PAINT ORANGE (-1475 1675);
DISPLAY INVISIBLE (-1475 1675);
FORCEPROP 2 LAST SEC_TYPE 0402
J 0
(-1475 1575);
DISPLAY 1.021277 (-1475 1575);
PAINT ORANGE (-1475 1575);
DISPLAY INVISIBLE (-1475 1575);
FORCEPROP 1 LAST PATH I388
J 0
(-1475 1525);
DISPLAY 0.978723 (-1475 1525);
PAINT WHITE (-1475 1525);
DISPLAY INVISIBLE (-1475 1525);
FORCEPROP 2 LAST CDS_LIB mstr_discrete
J 0
(-1425 1375);
PAINT ORANGE (-1425 1375);
DISPLAY INVISIBLE (-1425 1375);
FORCEADD OFFPAGE..2
(-800 1375);
FORCEPROP 2 LAST $XR0 149 
J 0
(-611 1375);
DISPLAY 0.638298 (-611 1375);
PAINT MONO (-611 1375);
FORCEPROP 1 LAST OFFPAGE TRUE
J 0
(-475 1250);
DISPLAY 0.872340 (-475 1250);
PAINT GREEN (-475 1250);
DISPLAY INVISIBLE (-475 1250);
FORCEPROP 2 LAST PATH I389
J 0
(-625 1450);
DISPLAY 1.021277 (-625 1450);
PAINT ORANGE (-625 1450);
DISPLAY INVISIBLE (-625 1450);
FORCEPROP 2 LAST CDS_LIB mstr_standard
J 0
(-800 1375);
PAINT ORANGE (-800 1375);
DISPLAY INVISIBLE (-800 1375);
FORCEPROP 1 LAST COMMENT_BODY TRUE
J 0
(-845 1280);
DISPLAY 0.872340 (-845 1280);
PAINT GREEN (-845 1280);
DISPLAY INVISIBLE (-845 1280);
FORCEADD RES..2
(-1850 4025);
FORCEPROP 1 LAST LOCATION R2N27
J 0
(-1805 4150);
DISPLAY 0.617021 (-1805 4150);
PAINT AQUA (-1805 4150);
FORCEPROP 1 LAST VALUE 4.75K
J 0
(-1805 4100);
DISPLAY 0.617021 (-1805 4100);
PAINT SKYBLUE (-1805 4100);
FORCEPROP 1 LASTPIN (-1850 4125) $PN 1
J 0
(-1845 4087);
DISPLAY 0.617021 (-1845 4087);
PAINT ORANGE (-1845 4087);
FORCEPROP 1 LAST PART_NUMBER G21796-072
J 0
(-1810 3900);
DISPLAY 0.617021 (-1810 3900);
PAINT BLUE (-1810 3900);
FORCEPROP 1 LAST TOLERANCE 1%
J 0
(-1805 4050);
DISPLAY 0.617021 (-1805 4050);
PAINT SKYBLUE (-1805 4050);
FORCEPROP 1 LAST PACK_TYPE 0402
J 0
(-1810 3850);
DISPLAY 0.617021 (-1810 3850);
PAINT SKYBLUE (-1810 3850);
FORCEPROP 1 LAST MATERIAL CHIP
J 0
(-1810 3950);
DISPLAY 0.617021 (-1810 3950);
PAINT SKYBLUE (-1810 3950);
FORCEPROP 1 LAST WATTAGE 1/16W
J 0
(-1810 4000);
DISPLAY 0.617021 (-1810 4000);
PAINT SKYBLUE (-1810 4000);
FORCEPROP 1 LASTPIN (-1850 3925) $PN 2
J 0
(-1845 3935);
DISPLAY 0.617021 (-1845 3935);
PAINT ORANGE (-1845 3935);
FORCEPROP 2 LAST SEC 1
J 0
(-1800 4250);
DISPLAY 0.680851 (-1800 4250);
PAINT MONO (-1800 4250);
DISPLAY INVISIBLE (-1800 4250);
FORCEPROP 2 LAST SEC_TYPE 0402
J 0
(-1800 4250);
DISPLAY 1.021277 (-1800 4250);
PAINT ORANGE (-1800 4250);
DISPLAY INVISIBLE (-1800 4250);
FORCEPROP 1 LAST PATH I97
J 0
(-1800 4200);
DISPLAY 0.978723 (-1800 4200);
PAINT WHITE (-1800 4200);
DISPLAY INVISIBLE (-1800 4200);
FORCEPROP 2 LAST ROOM BMC_MISC
J 0
(-1900 4125);
DISPLAY 1.021277 (-1900 4125);
PAINT ORANGE (-1900 4125);
DISPLAY INVISIBLE (-1900 4125);
FORCEPROP 2 LAST BOM_COST SM_CONTROLLER
J 0
(-1900 4175);
DISPLAY 1.021277 (-1900 4175);
PAINT ORANGE (-1900 4175);
DISPLAY INVISIBLE (-1900 4175);
FORCEPROP 2 LAST CDS_LOCATION R2N27
J 0
(-1805 4150);
DISPLAY 0.617021 (-1805 4150);
PAINT AQUA (-1805 4150);
DISPLAY INVISIBLE (-1805 4150);
FORCEPROP 2 LAST CDS_LIB mstr_discrete
J 0
(-1850 4025);
DISPLAY 1.361702 (-1850 4025);
PAINT ORANGE (-1850 4025);
DISPLAY INVISIBLE (-1850 4025);
FORCEADD DNS..2
(-7170 2195);
PAINT RED (-7170 2195);
FORCEPROP 2 LAST CDS_LIB mstr_misc
J 0
(-7170 2195);
PAINT ORANGE (-7170 2195);
DISPLAY INVISIBLE (-7170 2195);
FORCEPROP 1 LAST COMMENT_BODY TRUE
R 1
J 0
(-7095 1970);
DISPLAY 0.872340 (-7095 1970);
PAINT GREEN (-7095 1970);
DISPLAY INVISIBLE (-7095 1970);
FORCEADD CAD_NOTE..1
(-900 1825);
FORCEPROP 0 LAST L2 NEXT TO VCC PIN OF
J 2
(-675 1625);
DISPLAY 1.021277 (-675 1625);
PAINT ORANGE (-675 1625);
FORCEPROP 0 LAST L3 TTL1G07_A
J 2
(-675 1550);
DISPLAY 1.021277 (-675 1550);
PAINT ORANGE (-675 1550);
FORCEPROP 0 LAST L1 PLACE 0.1UF CAP
J 2
(-675 1700);
DISPLAY 1.021277 (-675 1700);
PAINT ORANGE (-675 1700);
FORCEPROP 2 LAST CDS_LIB mstr_symbols
J 0
(-900 1825);
PAINT ORANGE (-900 1825);
DISPLAY INVISIBLE (-900 1825);
FORCEPROP 1 LAST COMMENT_BODY TRUE
J 0
(-875 1925);
DISPLAY 0.978723 (-875 1925);
PAINT ORANGE (-875 1925);
DISPLAY INVISIBLE (-875 1925);
FORCEADD CAD_NOTE..1
(-2225 3075);
FORCEPROP 0 LAST L1 PLACE 0.1UF CAP NEXT TO VCC PIN
J 2
(-1975 2950);
DISPLAY 1.021277 (-1975 2950);
PAINT ORANGE (-1975 2950);
FORCEPROP 0 LAST L2 ON 74LVC2G14
J 2
(-1975 2875);
DISPLAY 1.021277 (-1975 2875);
PAINT ORANGE (-1975 2875);
FORCEPROP 1 LAST COMMENT_BODY TRUE
J 0
(-2200 3175);
DISPLAY 0.978723 (-2200 3175);
PAINT ORANGE (-2200 3175);
DISPLAY INVISIBLE (-2200 3175);
FORCEPROP 2 LAST CDS_LIB mstr_symbols
J 0
(-2225 3075);
PAINT ORANGE (-2225 3075);
DISPLAY INVISIBLE (-2225 3075);
FORCEADD INTEL_CORP_BPAGE..1
(0 0);
FORCEPROP 1 LAST CDS_CON_LAST_MODIFIED Tue Dec 01 11:52:09 2015
J 0
(-1425 325);
DISPLAY 1.361702 (-1425 325);
PAINT GREEN (-1425 325);
DISPLAY INVISIBLE (-1425 325);
FORCEPROP 1 LAST CUSTOM_TXT_CDS <CURRENT_DESIGN_SHEET> OF <TOTAL_DESIGN_SHEETS>
J 0
(-500 25);
PAINT GREEN (-500 25);
FORCEPROP 1 LAST CUSTOM_TXT_CDS <CON_LAST_MODIFIED>
J 0
(-1925 350);
PAINT GREEN (-1925 350);
FORCEPROP 2 LAST CUSTOM_TXT_CDS <XR_PAGE_TITLE>
J 0
(-7890 5250);
DISPLAY 0.638298 (-7890 5250);
PAINT PINK (-7890 5250);
DISPLAY INVISIBLE (-7890 5250);
FORCEPROP 1 LAST SCH_NUMBER H4694802
J 0
(-1300 150);
DISPLAY 1.212766 (-1300 150);
PAINT YELLOW (-1300 150);
FORCEPROP 1 LAST SCH_REV 2.420
J 0
(-250 150);
DISPLAY 0.978723 (-250 150);
PAINT YELLOW (-250 150);
FORCEPROP 1 LAST SCH_DEPT BESD
J 1
(-4450 100);
DISPLAY 1.212766 (-4450 100);
PAINT YELLOW (-4450 100);
FORCEPROP 1 LAST SCH_TITLE BMC MISC (2 OF 2)
J 0
(-7950 50);
DISPLAY 1.212766 (-7950 50);
PAINT ORANGE (-7950 50);
FORCEPROP 1 LAST SCH_ADDRESS2 P.O. BOX 58119
J 0
(-3975 75);
DISPLAY 0.617021 (-3975 75);
PAINT GREEN (-3975 75);
FORCEPROP 1 LAST SCH_ADDRESS3 Santa Clara, CA 95052-8119
J 0
(-3975 25);
DISPLAY 0.617021 (-3975 25);
PAINT GREEN (-3975 25);
FORCEPROP 1 LAST SCH_ADDRESS1 2200 Mission College Blvd.
J 0
(-3975 125);
DISPLAY 0.617021 (-3975 125);
PAINT GREEN (-3975 125);
FORCEPROP 1 LAST COMMENT_BODY TRUE
J 0
(12 12);
DISPLAY 0.617021 (12 12);
PAINT GREEN (12 12);
DISPLAY INVISIBLE (12 12);
FORCEPROP 2 LAST CDS_LIB mstr_symbols
J 0
(0 0);
DISPLAY 1.361702 (0 0);
PAINT ORANGE (0 0);
DISPLAY INVISIBLE (0 0);
FORCEPROP 2 LAST PAGE_BORDER TRUE
J 0
(-7890 5250);
DISPLAY 0.851064 (-7890 5250);
PAINT PINK (-7890 5250);
DISPLAY INVISIBLE (-7890 5250);
FORCEPROP 2 LAST CDS_XR_PAGE_TITLE CR-157 : @BASEBOARD_FAB2_LIB.BASEBOARD_FAB2(SCH_1):PAGE157
J 0
(-7890 5250);
DISPLAY 0.638298 (-7890 5250);
PAINT PINK (-7890 5250);
DISPLAY INVISIBLE (-7890 5250);
WIRE 16 -1 (-7525 2200)(-7275 2200);
WIRE 16 -1 (-7525 2200)(-7525 2425);
WIRE 16 -1 (-7525 2425)(-7525 2650);
WIRE 16 -1 (-7525 2425)(-7275 2425);
WIRE 16 -1 (-7525 2650)(-7275 2650);
WIRE 16 -1 (-7525 2650)(-7525 2875);
WIRE 16 -1 (-7525 2875)(-7525 3100);
WIRE 16 -1 (-7525 2875)(-7275 2875);
WIRE 16 -1 (-7525 3100)(-7275 3100);
WIRE 16 -1 (-7525 3100)(-7525 3425);
WIRE 16 -1 (-7525 3425)(-7525 3725);
WIRE 16 -1 (-7525 3425)(-7275 3425);
WIRE 16 -1 (-7525 3725)(-7275 3725);
WIRE 16 -1 (-7525 3975)(-7525 3725);
WIRE 16 -1 (-7525 4225)(-7525 3975);
WIRE 16 -1 (-7525 3975)(-7275 3975);
WIRE 16 -1 (-7525 4225)(-7300 4225);
WIRE 16 -1 (-7525 4600)(-7525 4225);
WIRE 16 -1 (-1850 4125)(-1850 4225);
WIRE 16 -1 (-6225 675)(-6225 575);
WIRE 16 -1 (-6225 1350)(-6225 1400);
WIRE 16 -1 (-5575 1750)(-5575 1825);
WIRE 16 -1 (-5575 825)(-5575 900);
WIRE 16 -1 (-2275 1625)(-2275 1675);
WIRE 16 -1 (-3200 1925)(-3200 2050);
WIRE 16 -1 (-4775 2375)(-4625 2375);
WIRE 16 -1 (-4775 2250)(-4775 2375);
WIRE 16 -1 (-5250 4625)(-5250 4025);
WIRE 16 -1 (-5250 4025)(-5025 4025);
WIRE 16 -1 (-1825 3175)(-1825 3025);
WIRE 16 -1 (-1825 2675)(-1825 2825);
WIRE 16 -1 (-500 1625)(-500 1525);
WIRE 16 -1 (-500 1900)(-500 1825);
WIRE 16 -1 (-3950 2750)(-3950 2875);
WIRE 3 2175 (-1750 1225)(-225 1225);
WIRE 3 2175 (-1750 1225)(-1750 1075);
WIRE 3 2175 (-225 1225)(-225 1075);
WIRE 3 2175 (-1750 1075)(-225 1075);
WIRE 16 3135 (-4400 375)(-4400 1750);
WIRE 16 -1 (-1825 1150)(-1600 1150);
WIRE 16 -1 (-850 1150)(-1600 1150);
FORCEPROP 2 LAST SIG_NAME FM_TPM_PRES_RST_N
J 0
(-1435 1160);
DISPLAY 0.680851 (-1435 1160);
PAINT ORANGE (-1435 1160);
WIRE 16 -1 (-1600 875)(-1600 1150);
WIRE 16 -1 (-1600 875)(-1550 875);
WIRE 16 -1 (-1350 875)(-850 875);
FORCEPROP 2 LAST SIG_NAME FM_BMC_ENABLE_N
J 0
(-1260 885);
DISPLAY 0.617021 (-1260 885);
PAINT ORANGE (-1260 885);
WIRE 16 -1 (-5575 1425)(-4900 1425);
FORCEPROP 2 LAST SIG_NAME H_CPU0_FAST_WAKE_LVT3_N
J 0
(-5460 1435);
DISPLAY 0.617021 (-5460 1435);
PAINT ORANGE (-5460 1435);
WIRE 16 -1 (-5575 1425)(-5575 1550);
WIRE 16 -1 (-5575 1425)(-5575 1300);
WIRE 16 -1 (-1325 1375)(-850 1375);
FORCEPROP 2 LAST SIG_NAME RST_BMC_DDR3_BUF_IN_N
J 0
(-1260 1385);
DISPLAY 0.617021 (-1260 1385);
PAINT ORANGE (-1260 1385);
WIRE 16 3135 (-2775 2125)(-150 2125);
WIRE 16 3135 (-2775 1800)(-2775 2125);
WIRE 16 3135 (-5050 1800)(-2775 1800);
WIRE 16 3135 (-5050 1800)(-5050 3025);
WIRE 16 -1 (-1300 2375)(-875 2375);
FORCEPROP 2 LAST SIG_NAME FP_NMI_BTN_N
J 0
(-1210 2385);
DISPLAY 0.617021 (-1210 2385);
PAINT ORANGE (-1210 2385);
WIRE 16 -1 (-1850 3925)(-1850 3825);
WIRE 16 -1 (-1850 3825)(-1300 3825);
FORCEPROP 2 LAST SIG_NAME FM_BMC_NMI_N
J 0
(-1585 3835);
DISPLAY 0.617021 (-1585 3835);
PAINT ORANGE (-1585 3835);
WIRE 16 -1 (-1950 3825)(-1850 3825);
WIRE 16 -1 (-2000 2375)(-1500 2375);
FORCEPROP 2 LAST SIG_NAME FP_NMI_BTN_R_N
J 0
(-1910 2385);
DISPLAY 0.617021 (-1910 2385);
PAINT ORANGE (-1910 2385);
FORCEPROP 2 LASTPROP $XRERR UNIQUE?
J 0
(-2150 2385);
DISPLAY 0.638298 (-2150 2385);
PAINT MONO (-2150 2385);
DISPLAY INVISIBLE (-2150 2385);
WIRE 16 -1 (-2650 1150)(-2275 1150);
WIRE 16 -1 (-2275 1425)(-2275 1150);
WIRE 16 -1 (-2075 1150)(-2275 1150);
WIRE 16 -1 (-2025 1150)(-2075 1150);
WIRE 16 -1 (-2075 1150)(-2075 1375);
WIRE 16 -1 (-2075 1375)(-1525 1375);
WIRE 16 -1 (-2850 3825)(-2150 3825);
FORCEPROP 2 LAST SIG_NAME FM_NMI_EVENT_N
J 0
(-2860 3835);
DISPLAY 0.617021 (-2860 3835);
PAINT ORANGE (-2860 3835);
WIRE 16 -1 (-2750 2375)(-2250 2375);
FORCEPROP 2 LAST SIG_NAME FP_NMI_BTN
J 0
(-2610 2385);
DISPLAY 0.617021 (-2610 2385);
PAINT ORANGE (-2610 2385);
FORCEPROP 2 LASTPROP $XRERR UNIQUE?
J 0
(-2850 2385);
DISPLAY 0.638298 (-2850 2385);
PAINT MONO (-2850 2385);
DISPLAY INVISIBLE (-2850 2385);
WIRE 16 -1 (-3550 2375)(-3200 2375);
FORCEPROP 2 LAST SIG_NAME FP_NMI_BTN_OUT_N
J 0
(-3535 2385);
DISPLAY 0.617021 (-3535 2385);
PAINT ORANGE (-3535 2385);
FORCEPROP 2 LASTPROP $XRERR UNIQUE?
J 0
(-3775 2385);
DISPLAY 0.638298 (-3775 2385);
PAINT MONO (-3775 2385);
DISPLAY INVISIBLE (-3775 2385);
WIRE 16 -1 (-3200 2375)(-3000 2375);
WIRE 16 -1 (-3200 2250)(-3200 2375);
WIRE 16 -1 (-3750 2375)(-3950 2375);
WIRE 16 -1 (-3950 2550)(-3950 2375);
WIRE 16 -1 (-3950 2375)(-4125 2375);
FORCEPROP 2 LAST SIG_NAME FP_NMI_BTN_OUT_R_N
J 0
(-4160 2385);
DISPLAY 0.617021 (-4160 2385);
PAINT ORANGE (-4160 2385);
FORCEPROP 2 LASTPROP $XRERR UNIQUE?
J 0
(-4400 2385);
DISPLAY 0.638298 (-4400 2385);
PAINT MONO (-4400 2385);
DISPLAY INVISIBLE (-4400 2385);
WIRE 16 -1 (-3450 1150)(-2900 1150);
FORCEPROP 2 LAST SIG_NAME PWRGD_DSW_PWROK
J 0
(-3385 1160);
DISPLAY 0.617021 (-3385 1160);
PAINT ORANGE (-3385 1160);
WIRE 16 -1 (-4825 4025)(-3750 4025);
FORCEPROP 2 LAST SIG_NAME FM_CPLD_BMC_PWRDN_N
J 0
(-4610 4035);
DISPLAY 0.617021 (-4610 4035);
PAINT ORANGE (-4610 4035);
WIRE 16 3135 (-5050 3050)(-5050 3425);
WIRE 16 3135 (-5050 3425)(-125 3425);
WIRE 16 -1 (-7100 4225)(-6025 4225);
FORCEPROP 2 LAST SIG_NAME IRQ_MEZZ_LAN_ALERT_N
J 0
(-6910 4235);
DISPLAY 0.617021 (-6910 4235);
PAINT ORANGE (-6910 4235);
WIRE 16 -1 (-7075 3425)(-6000 3425);
FORCEPROP 2 LAST SIG_NAME FM_BMC_CPLD_MP_RST_N
J 0
(-6860 3435);
DISPLAY 0.617021 (-6860 3435);
PAINT ORANGE (-6860 3435);
WIRE 16 -1 (-7075 2200)(-6000 2200);
FORCEPROP 2 LAST SIG_NAME FM_BIOS_TOP_SWAP
J 0
(-6860 2210);
DISPLAY 0.617021 (-6860 2210);
PAINT ORANGE (-6860 2210);
WIRE 16 -1 (-7075 2425)(-6000 2425);
FORCEPROP 2 LAST SIG_NAME FM_BMC_CPLD_GPO
J 0
(-6860 2435);
DISPLAY 0.617021 (-6860 2435);
PAINT ORANGE (-6860 2435);
WIRE 16 -1 (-7075 2650)(-6000 2650);
FORCEPROP 2 LAST SIG_NAME FM_ADR_SMI_GPIO_N
J 0
(-6860 2660);
DISPLAY 0.617021 (-6860 2660);
PAINT ORANGE (-6860 2660);
WIRE 16 -1 (-7075 2875)(-6000 2875);
FORCEPROP 2 LAST SIG_NAME FM_MP_PS_REDUNDANT_LOST_N
J 0
(-6860 2885);
DISPLAY 0.617021 (-6860 2885);
PAINT ORANGE (-6860 2885);
WIRE 16 -1 (-7075 3100)(-6000 3100);
FORCEPROP 2 LAST SIG_NAME FM_MP_PS_FAIL_N
J 0
(-6860 3110);
DISPLAY 0.617021 (-6860 3110);
PAINT ORANGE (-6860 3110);
WIRE 16 -1 (-7075 3725)(-6000 3725);
FORCEPROP 2 LAST SIG_NAME FP_NMI_BTN_N
J 0
(-6860 3735);
DISPLAY 0.617021 (-6860 3735);
PAINT ORANGE (-6860 3735);
WIRE 16 -1 (-7075 3975)(-6000 3975);
FORCEPROP 2 LAST SIG_NAME IRQ_OOB_MGMT_RISER_ALERT_N
J 0
(-6885 3985);
DISPLAY 0.617021 (-6885 3985);
PAINT ORANGE (-6885 3985);
WIRE 16 -1 (-6225 1000)(-5775 1000);
FORCEPROP 2 LAST SIG_NAME H_CPU0_FAST_WAKE
J 0
(-6210 1010);
DISPLAY 0.617021 (-6210 1010);
PAINT ORANGE (-6210 1010);
FORCEPROP 2 LASTPROP $XRERR UNIQUE?
J 0
(-6450 1010);
DISPLAY 0.638298 (-6450 1010);
PAINT MONO (-6450 1010);
DISPLAY INVISIBLE (-6450 1010);
WIRE 16 -1 (-6225 1000)(-6225 1150);
WIRE 16 -1 (-6225 875)(-6225 1000);
WIRE 16 -1 (-6375 775)(-6875 775);
FORCEPROP 2 LAST SIG_NAME H_CPU0_FAST_WAKE_B_N
J 0
(-6835 785);
DISPLAY 0.617021 (-6835 785);
PAINT ORANGE (-6835 785);
FORCEPROP 2 LASTPROP $XRERR UNIQUE?
J 0
(-7075 785);
DISPLAY 0.638298 (-7075 785);
PAINT MONO (-7075 785);
DISPLAY INVISIBLE (-7075 785);
WIRE 16 -1 (-7525 775)(-7075 775);
FORCEPROP 2 LAST SIG_NAME H_CPU0_FAST_WAKE_N
J 0
(-7510 785);
DISPLAY 0.617021 (-7510 785);
PAINT ORANGE (-7510 785);
DOT 1 (-1850 3825);
DOT 1 (-3200 2375);
DOT 1 (-3950 2375);
DOT 1 (-2275 1150);
DOT 1 (-2075 1150);
DOT 1 (-7525 4225);
DOT 1 (-5575 1425);
DOT 1 (-7525 3975);
DOT 1 (-7525 3725);
DOT 1 (-7525 3425);
DOT 1 (-7525 3100);
DOT 1 (-7525 2650);
DOT 1 (-7525 2875);
DOT 1 (-7525 2425);
DOT 1 (-6225 1000);
DOT 1 (-1600 1150);
FORCENOTE
NMI BUTTON
(-4725 3125) 0;
DISPLAY LEFT (-4725 3125);
DISPLAY 1.021277 (-4725 3125);
PAINT PURPLE (-4725 3125);
FORCENOTE
ROOM=SM_CONTROLLER
(-7764 315) 0;
DISPLAY LEFT (-7764 315);
DISPLAY 0.617021 (-7764 315);
PAINT PURPLE (-7764 315);
FORCENOTE
BMC DISABLE JUMPER (ON PAGE 134 PINS 3 AND 5)
(-4275 1625) 0;
DISPLAY LEFT (-4275 1625);
DISPLAY 1.276596 (-4275 1625);
PAINT PURPLE (-4275 1625);
FORCENOTE
TP FAB1 FOR BMC TPM 1120
(-1150 1250) 0;
DISPLAY LEFT (-1150 1250);
DISPLAY 1.021277 (-1150 1250);
PAINT RED (-1150 1250);
QUIT
